G04 ================== begin FILE IDENTIFICATION RECORD ==================*
G04 Layout Name:  14545-sa.brd*
G04 Film Name:    L3*
G04 File Format:  Gerber RS274X*
G04 File Origin:  Cadence Allegro 16.5-S056*
G04 Origin Date:  Fri Aug 01 17:58:43 2014*
G04 *
G04 Layer:  VIA CLASS/L3*
G04 Layer:  PIN/L3*
G04 Layer:  ETCH/L3*
G04 Layer:  DRAWING FORMAT/LAYER_PCB_STORY*
G04 Layer:  DRAWING FORMAT/LAYER_L3*
G04 *
G04 Offset:    (0.00 0.00)*
G04 Mirror:    No*
G04 Mode:      Positive*
G04 Rotation:  0*
G04 FullContactRelief:  No*
G04 UndefLineWidth:     6.00*
G04 ================== end FILE IDENTIFICATION RECORD ====================*
%FSLAX35Y35*MOIN*%
%IR0*IPPOS*OFA0.00000B0.00000*MIA0B0*SFA1.00000B1.00000*%
%ADD12O,.103X.06*%
%ADD13C,.022*%
%ADD10C,.028*%
%ADD14C,.173*%
%ADD11C,.156*%
%ADD15C,.02*%
%ADD16C,.03*%
%ADD17C,.025*%
%ADD18C,.006*%
%ADD19C,.0045*%
%ADD20C,.00575*%
%ADD21O,.12702X.08402*%
%ADD27C,.05204*%
%ADD26C,.04604*%
%ADD23C,.09704*%
%ADD22C,.11504*%
%ADD24C,.17004*%
%ADD25C,.18004*%
%ADD28C,.19704*%
G75*
%LPD*%
G75*
G36*
G01X709658Y1826214D02*
X161259Y1600546D01*
X161179Y1600584D01*
G03X157965Y1599050I-979J-2084D01*
G01X157949Y1598984D01*
X157753Y1598826D01*
X157670Y1598836D01*
G03X155099Y1596498I-270J-2286D01*
G02X154699Y1596090I-400J-8D01*
G01X97217D01*
X76014Y1617293D01*
Y1623704D01*
X86976Y1634666D01*
Y1634667D01*
X93464Y1641156D01*
Y1642515D01*
X93499Y1642550D01*
Y1648603D01*
X93652Y1649374D01*
Y1652438D01*
X93499Y1653209D01*
Y1660550D01*
X93464Y1660585D01*
Y1660703D01*
X75990Y1678178D01*
Y1690245D01*
G03X74425Y1694301I-1490J1755D01*
G02X74012Y1694700I-13J400D01*
G01Y1755966D01*
X73999Y1755978D01*
Y1775398D01*
G02X74399Y1775798I400J0D01*
G01X74400D01*
G03X74401Y1780402I0J2302D01*
G01X74399D01*
G02X73999Y1780802I0J400D01*
G01Y1796837D01*
G02X74685Y1797117I400J0D01*
G03Y1803907I3465J3395D01*
G02X73999Y1804187I-286J280D01*
G01Y1809332D01*
G03X74056Y1815257I-2951J2991D01*
G01X73999Y1815315D01*
Y1815760D01*
X78344D01*
G03Y1818740I1755J1490D01*
G01X72810D01*
X44499Y1847050D01*
X5499D01*
X3000Y1849549D01*
Y1945000D01*
X3548Y1945548D01*
X3689Y1945409D01*
G03X3885Y1948863I1614J1641D01*
G01X3746Y1948754D01*
X3000Y1949500D01*
Y1988000D01*
X4000Y1989000D01*
X1029000D01*
X1029500Y1988500D01*
Y1988499D01*
X1029999Y1988000D01*
Y1744501D01*
X1030000Y1744500D01*
Y1690300D01*
X1027100Y1687400D01*
X1025465D01*
G02X1025188Y1688088I0J400D01*
G03X1017367Y1685931I-5897J6124D01*
G02X1017559Y1685259I-91J-389D01*
G01X1015600Y1683300D01*
Y1625800D01*
X1013900Y1624100D01*
X989772D01*
G02X989377Y1624559I0J400D01*
G03X986325Y1622732I-2277J341D01*
G02X986473Y1622073I-135J-376D01*
G01X984400Y1620000D01*
Y1610600D01*
X989000Y1606000D01*
X1014500D01*
X1016200Y1604300D01*
Y1429300D01*
X1020000Y1425500D01*
X1027500D01*
X1030000Y1423000D01*
Y1270551D01*
X1029999Y1270550D01*
Y4000D01*
X1028999Y3000D01*
X4100D01*
X3100Y4000D01*
Y207500D01*
X5600Y210000D01*
X25000D01*
X27000Y212000D01*
Y221000D01*
X23500Y224500D01*
X5600D01*
X3100Y227000D01*
Y405500D01*
X7100Y409500D01*
X22900D01*
X27000Y413600D01*
Y415553D01*
G02X27622Y415885I400J-1D01*
G03X31200Y417864I1277J1915D01*
G01Y417902D01*
X31197Y417990D01*
X37328Y424121D01*
G02X38010Y423838I282J-283D01*
G01Y414691D01*
G02X37357Y414382I-400J1D01*
G03Y410818I-1457J-1782D01*
G02X38010Y410509I253J-310D01*
G01Y386017D01*
X28290Y376297D01*
X28202Y376300D01*
G03X30400Y374064I-103J-2300D01*
G01Y374102D01*
X30397Y374190D01*
X40990Y384783D01*
Y430083D01*
X61210Y450303D01*
X61298Y450300D01*
G03X63681Y452907I102J2300D01*
G02X64214Y453336I396J53D01*
G03X63245Y456990I786J2164D01*
G01X57283D01*
X36010Y435717D01*
Y427017D01*
X32347Y423353D01*
X31500Y424200D01*
X29168D01*
G02X28769Y424577I0J400D01*
G01X28846Y426638D01*
X28844D01*
X28835Y426829D01*
G03X24219Y426908I-2311J-110D01*
G01X24197Y426640D01*
X24107Y424200D01*
X23400D01*
X21500Y426100D01*
Y517500D01*
X26200Y522200D01*
X33799D01*
G02X34197Y521763I0J-400D01*
G03X34188Y521550I2302J-204D01*
G01Y517775D01*
G03X38804Y517599I2311J0D01*
G01X38810Y517687D01*
Y521560D01*
G03X38801Y521763I-2311J-1D01*
G02X39199Y522200I398J37D01*
G01X55900D01*
X63350Y514750D01*
X63332Y514648D01*
G03X65997Y511983I2267J-398D01*
G01X66099Y512001D01*
X67700Y510400D01*
X88300D01*
X91100Y507600D01*
X97900D01*
X101300Y511000D01*
Y517800D01*
X96900Y522200D01*
X68600D01*
X59643Y531157D01*
G02X59905Y531839I283J283D01*
G03X62310Y533971I98J2311D01*
G01X62317Y534065D01*
X62313Y537633D01*
X62304Y537738D01*
G03X57686Y537547I-2305J-188D01*
G01X57690Y534147D01*
G03X57692Y534052I2313J1D01*
G02X57010Y533790I-399J21D01*
G01X55500Y535300D01*
X22500D01*
X21500Y536300D01*
Y659500D01*
X22400Y660400D01*
X23620D01*
X25324Y658695D01*
G02X25341Y658148I-283J-283D01*
G03X25179Y657961I1658J-1600D01*
G03X24700Y656734I1818J-1417D01*
G01Y656725D01*
X24688Y656656D01*
X24525Y653803D01*
X24427Y652086D01*
X24430D01*
X24434Y651954D01*
G03X24598Y651104I2303J4D01*
G03X24716Y650852I2141J849D01*
G03X27697Y649863I2021J1104D01*
G03X29033Y651754I-959J2095D01*
G01Y651760D01*
X29050Y651878D01*
Y651884D01*
X29051Y651905D01*
X29054Y651960D01*
Y651964D01*
X29165Y653899D01*
X29309Y656421D01*
X29302Y656422D01*
Y656642D01*
X29301Y656655D01*
X29300Y656661D01*
X29299Y656675D01*
G03X29111Y657469I-2300J-125D01*
G03X28920Y657820I-2111J-921D01*
G02X29272Y658410I352J190D01*
G01X29402D01*
X39010Y648802D01*
Y643183D01*
X39203Y642990D01*
X39200Y642902D01*
Y642864D01*
G03X42135Y645013I2301J-64D01*
G01X41990Y645055D01*
Y650036D01*
X30636Y661390D01*
X26843D01*
X25700Y662532D01*
Y663700D01*
X26900Y664900D01*
X37218D01*
X41925Y660192D01*
G02X41890Y659595I-282J-283D01*
G03X44712Y655248I1609J-2045D01*
G02X45298Y654894I186J-354D01*
G01Y640905D01*
X41690Y637297D01*
X41602Y637300D01*
G03X39461Y636070I-102J-2300D01*
G01X39436Y636021D01*
X39243Y635902D01*
X39150Y635939D01*
G03X40339Y632730I-850J-2140D01*
G01X40364Y632779D01*
X40557Y632898D01*
X40650Y632861D01*
G03X43800Y635064I849J2139D01*
G01Y635102D01*
X43797Y635190D01*
X48278Y639671D01*
Y640217D01*
G02X48725Y640614I400J0D01*
G03Y645186I274J2286D01*
G02X48278Y645583I-47J397D01*
G01Y658053D01*
X41315Y665015D01*
X41700Y665400D01*
Y666800D01*
X33000Y675500D01*
Y682000D01*
X37100Y686100D01*
Y688167D01*
X38314Y689380D01*
Y703193D01*
X34514Y706993D01*
Y742867D01*
X35866Y744219D01*
Y775916D01*
X57772Y797823D01*
G02X58454Y797540I282J-283D01*
G01Y645815D01*
X47291Y634652D01*
X47203Y634655D01*
G03X49401Y632456I-102J-2300D01*
G01X49397Y632544D01*
X50266Y633414D01*
G02X50838Y633407I283J-283D01*
G03X54093Y636662I1662J1593D01*
G02X54086Y637234I276J289D01*
G01X61434Y644581D01*
Y801484D01*
X62949Y803000D01*
Y816065D01*
G02X63667Y816307I400J0D01*
G03X66989Y819455I1833J1393D01*
G01Y822388D01*
X66182Y823195D01*
G02X66489Y823877I283J283D01*
G03X66748Y823870I243J4194D01*
G01X71048D01*
G03X74362Y830654I0J4201D01*
G02X74677Y831300I315J246D01*
G01X78800D01*
X84528Y837028D01*
G02X85210Y836745I282J-283D01*
G01Y815283D01*
X86410Y814083D01*
Y658617D01*
X86072Y658279D01*
G02X85390Y658562I-282J283D01*
G01Y814217D01*
X82797Y816810D01*
X82800Y816898D01*
Y816936D01*
G03X80602Y814700I-2301J64D01*
G01X80690Y814703D01*
X82410Y812983D01*
Y666789D01*
G02X81857Y666420I-400J0D01*
G03X80499Y666862I-1359J-1870D01*
G01X76999D01*
G03Y662238I0J-2312D01*
G01X80499D01*
G03X81857Y662680I-1J2312D01*
G02X82410Y662311I153J-369D01*
G01Y657217D01*
X43483Y618290D01*
X31483D01*
X26990Y613797D01*
X26902Y613800D01*
G03X29100Y611564I-103J-2300D01*
G01Y611602D01*
X29097Y611690D01*
X32717Y615310D01*
X42138D01*
G02X42421Y614628I0J-400D01*
G01X41590Y613797D01*
X41502Y613800D01*
G03X39860Y613211I-102J-2300D01*
G02X39588Y613215I-134J149D01*
G03X39539Y609839I-1589J-1665D01*
G02X39811Y609835I134J-149D01*
G03X40089Y609608I1590J1664D01*
G01X40129Y609580D01*
X40231Y609389D01*
X40179Y609294D01*
G03X43583Y606354I2023J-1098D01*
G02X43863Y606314I120J-160D01*
G03X47851Y608522I1838J1386D01*
G02X48136Y609055I374J143D01*
G03X48773Y613296I-510J2245D01*
G02X48690Y613925I200J346D01*
G01X93403Y658638D01*
G02X94086Y658356I283J-283D01*
G01Y648514D01*
X48334Y602763D01*
Y589337D01*
X50960Y586711D01*
Y561742D01*
G02X50448Y561359I-400J1D01*
G03Y556941I-649J-2209D01*
G02X50960Y556558I112J-384D01*
G01Y553967D01*
X49253Y552259D01*
G02X48575Y552602I-283J283D01*
G03X45865Y555211I-2276J348D01*
G02X45391Y555640I-76J393D01*
G03X41028Y556855I-2292J210D01*
G02X40453Y556692I-360J174D01*
G03X41288Y553745I-1236J-1942D01*
G02X41863Y553908I360J-174D01*
G03X43533Y553589I1236J1942D01*
G02X44007Y553160I76J-393D01*
G03X46647Y550674I2292J-210D01*
G02X46990Y549996I60J-395D01*
G01X45780Y548786D01*
G02X45108Y548978I-283J283D01*
G03X42339Y546209I-2241J-528D01*
G02X42531Y545537I-91J-389D01*
G01X38083Y541090D01*
X28954D01*
G03Y538110I-1755J-1490D01*
G01X39317D01*
X53940Y552733D01*
Y553688D01*
G02X54622Y553971I400J0D01*
G01X65883Y542710D01*
X72266D01*
X72276Y542709D01*
G03X70932Y546685I224J2291D01*
G02X70266Y546907I-272J293D01*
G03X67898Y548800I-2266J-407D01*
G01X67810Y548797D01*
X57490Y559117D01*
Y589417D01*
X54864Y592043D01*
Y600057D01*
X80268Y625461D01*
G02X80839Y625455I283J-283D01*
G03X84094Y628710I1660J1595D01*
G02X84088Y629281I277J288D01*
G01X101530Y646723D01*
G02X102212Y646440I282J-283D01*
G01Y600781D01*
X102803Y600190D01*
X102800Y600102D01*
Y600064D01*
G03X105369Y602286I2301J-64D01*
G01X105192Y602307D01*
Y602495D01*
G02X105800Y602836I400J-1D01*
G03X107635Y607013I1200J1964D01*
G01X107490Y607055D01*
Y801194D01*
G02X108157Y801491I400J0D01*
G03X108919Y801035I1541J1710D01*
G02X109141Y800479I-136J-376D01*
G03X109358Y798070I2059J-1029D01*
G02X109284Y797515I-320J-240D01*
G03X112542Y797080I1416J-1815D01*
G02X112616Y797635I320J240D01*
G03X111981Y801615I-1416J1815D01*
G02X111759Y802171I136J376D01*
G03X111448Y804698I-2059J1029D01*
G02X111458Y804970I152J131D01*
G03X111696Y807949I-1627J1629D01*
G01X111678Y807974D01*
X111638Y808092D01*
X111708Y808243D01*
X111738Y808271D01*
G03X111888Y811538I-1543J1708D01*
G01X111835Y811675D01*
X111888Y811811D01*
X111913Y811838D01*
G03X108509Y811820I-1710J1541D01*
G01X108562Y811683D01*
X108509Y811547D01*
X108484Y811520D01*
G03X108330Y808628I1711J-1541D01*
G01X108348Y808603D01*
X108388Y808485D01*
X108318Y808333D01*
X108288Y808306D01*
G03X108177Y808199I1541J-1710D01*
G02X107490Y808477I-287J278D01*
G01Y912117D01*
X96990Y922617D01*
Y957383D01*
X103490Y963883D01*
Y966665D01*
G03X104394Y968692I-1390J1835D01*
G01X104386Y968785D01*
X115140Y979538D01*
Y1050033D01*
X126490Y1061383D01*
Y1065883D01*
X128117Y1067510D01*
X143117D01*
X147440Y1071834D01*
Y1109509D01*
X98690Y1158260D01*
Y1308883D01*
X112043Y1322237D01*
G02X112726Y1321954I283J-283D01*
G01Y1321666D01*
X113229Y1321163D01*
X113321Y1321170D01*
G02X113605Y1321175I182J-2295D01*
G03X114024Y1321574I19J400D01*
G01Y1324218D01*
X115669Y1325862D01*
X115786Y1325824D01*
G03X118238Y1326505I713J2189D01*
G02X118832Y1326517I302J-262D01*
G03X118768Y1329604I1675J1579D01*
G02X118174Y1329592I-302J262D01*
G03X116150Y1330288I-1675J-1579D01*
G02X115690Y1330683I-60J395D01*
G01Y1336883D01*
X116845Y1338038D01*
G02X117478Y1337947I282J-283D01*
G03X120988Y1340805I2021J1103D01*
G01Y1358029D01*
G02X121661Y1358321I400J-1D01*
G03X123500Y1357598I1840J1979D01*
G01X126390D01*
G02X126776Y1357095I0J-400D01*
G03X127894Y1354480I2224J-596D01*
G01X127920Y1354466D01*
X129698Y1352689D01*
Y1339789D01*
X137966Y1331520D01*
X137980Y1331494D01*
G03X141531Y1330881I2019J1106D01*
G02X142079Y1330866I266J-299D01*
G03X145691Y1331344I1621J1634D01*
G02X146293Y1331451I346J-200D01*
G03X148023Y1330824I1730J2074D01*
G02X148422Y1330424I-1J-400D01*
G01Y1325736D01*
X146320Y1323634D01*
X146294Y1323620D01*
G03X149424Y1320499I1107J-2020D01*
G01X149438Y1320524D01*
X152826Y1323912D01*
Y1329980D01*
X153926Y1331081D01*
Y1335969D01*
X152826Y1337070D01*
Y1363288D01*
X146712Y1369402D01*
X125388D01*
X124020Y1368034D01*
X123994Y1368020D01*
G03X122812Y1366257I1106J-2019D01*
G02X122205Y1365961I-397J45D01*
G03X118936Y1365018I-1205J-1961D01*
G02X118294Y1364912I-359J177D01*
G01X118072Y1365134D01*
Y1366245D01*
X117898Y1366267D01*
G02X116890Y1366655I300J2283D01*
G01Y1400217D01*
X94190Y1422917D01*
Y1531238D01*
G02X94872Y1531521I400J0D01*
G01X97383Y1529010D01*
X152617D01*
X161117Y1537510D01*
X318433D01*
X343035Y1512908D01*
X387300D01*
Y1512900D01*
X388300Y1511900D01*
X391100D01*
X391319Y1512119D01*
X391382Y1512130D01*
G03X392712Y1515936I-383J2269D01*
G01X392688Y1515963D01*
X392635Y1516098D01*
X392688Y1516233D01*
X392712Y1516260D01*
G03X392940Y1516560I-1713J1538D01*
G01X736951D01*
X748001Y1527610D01*
X748969D01*
G02X749240Y1526916I0J-400D01*
G03X749060Y1523266I1760J-1916D01*
G02Y1522734I-299J-266D01*
G03Y1519266I1940J-1734D01*
G02Y1518734I-299J-266D01*
G03X752940I1940J-1734D01*
G02Y1519266I299J266D01*
G03Y1522734I-1940J1734D01*
G02Y1523266I299J266D01*
G03X752760Y1526916I-1940J1734D01*
G02X753031Y1527610I271J294D01*
G01X770408D01*
X771708Y1526310D01*
X780067D01*
X781827Y1528071D01*
G02X782464Y1527975I283J-283D01*
G03X785574Y1531085I2035J1075D01*
G02X785478Y1531722I187J354D01*
G01X792822Y1539066D01*
X792952Y1539000D01*
G03X794001Y1543352I1047J2050D01*
G02X793801Y1543552I0J200D01*
G03X790370Y1541544I-2302J-2D01*
G02X790456Y1540913I-197J-348D01*
G01X778833Y1529290D01*
X777219D01*
G02X776823Y1529743I0J400D01*
G03X776216Y1531630I-2281J307D01*
G02X776221Y1532185I291J275D01*
G03X772408Y1533024I-1644J1611D01*
G02X772032Y1532490I-376J-134D01*
G01X745883D01*
X739433Y1526040D01*
X348392D01*
G03X349426Y1523060I-1068J-2040D01*
G01X738272D01*
G02X738555Y1522378I0J-400D01*
G01X735717Y1519540D01*
X392504D01*
G03X388702Y1517944I-1505J-1742D01*
G01X388699Y1517898D01*
X387550Y1515888D01*
X344269D01*
X319667Y1540490D01*
X159883D01*
X151383Y1531990D01*
X100045D01*
G02X99764Y1532674I0J400D01*
G03X100412Y1533914I-1620J1636D01*
G01X100424Y1533984D01*
X100620Y1534153D01*
X100700Y1534150D01*
G03X102555Y1534960I100J2300D01*
G01X153067D01*
X172667Y1554560D01*
X278244D01*
G03X281609Y1554405I1755J1490D01*
G02X281889I140J-143D01*
G03X285642Y1555210I1610J1645D01*
G01X363057D01*
X363871Y1554396D01*
X363861Y1554300D01*
G03X366207Y1556351I2288J-250D01*
G01X366127Y1556353D01*
X364291Y1558190D01*
X357043D01*
G02X356667Y1558724I1J400D01*
G03X352422Y1560490I-2167J776D01*
G01X332984D01*
G02X332587Y1560935I0J400D01*
G03X328013I-2287J265D01*
G02X327616Y1560490I-397J-45D01*
G01X171683D01*
X152533Y1541340D01*
X101654D01*
G03X99698Y1542143I-1755J-1490D01*
G02X99264Y1542541I-34J398D01*
G01Y1543969D01*
G02X99713Y1544366I400J0D01*
G03X102276Y1546994I287J2284D01*
G01X102261Y1547094D01*
X110114Y1554947D01*
Y1560788D01*
X128212Y1578886D01*
X287019D01*
G02X287416Y1578436I0J-400D01*
G03X288275Y1576164I2582J-322D01*
G02Y1575564I-264J-300D01*
G03Y1571664I1723J-1950D01*
G02Y1571064I-264J-300D01*
G03X291732Y1567174I1723J-1950D01*
G02X292264I266J-299D01*
G03X295721Y1571064I1734J1940D01*
G02Y1571664I264J300D01*
G03Y1575564I-1723J1950D01*
G02Y1576164I264J300D01*
G03X296580Y1578436I-1723J1950D01*
G02X296977Y1578886I397J50D01*
G01X330342D01*
G02X330735Y1578414I0J-400D01*
G03X335265I2265J-414D01*
G02X335658Y1578886I393J72D01*
G01X336008D01*
X336283Y1578610D01*
X395832D01*
X398702Y1575740D01*
X398699Y1575642D01*
Y1575618D01*
G03X400897Y1577850I2301J-68D01*
G01X400809Y1577847D01*
X397928Y1580728D01*
G02X398211Y1581410I283J282D01*
G01X933897D01*
X978236Y1625749D01*
G02X978916Y1625516I283J-283D01*
G03X981483Y1628084I2284J284D01*
G02X981250Y1628764I50J397D01*
G01X981404Y1628918D01*
X983494Y1631010D01*
Y1634290D01*
X986210Y1637005D01*
X986298Y1637002D01*
G03X986145Y1641590I101J2300D01*
G02X985700Y1641987I-45J398D01*
G01Y1665745D01*
G03X982722I-1489J1755D01*
G01Y1661832D01*
G02X982096Y1661502I-400J1D01*
G03X979749Y1661648I-1296J-1902D01*
G01X979653Y1661599D01*
X979461Y1661706D01*
X979434Y1661748D01*
G03X976213Y1662409I-1934J-1248D01*
G02X975590Y1662740I-223J332D01*
G01Y1663483D01*
X977810Y1665703D01*
X977898Y1665700D01*
G03X976876Y1670009I102J2300D01*
G02X976283Y1670408I-196J349D01*
G03X971700Y1670598I-2283J292D01*
G01X971703Y1670510D01*
X968410Y1667217D01*
Y1663093D01*
X967202Y1661884D01*
Y1653802D01*
G03X967206Y1653743I400J-3D01*
G02X966928Y1653302I-395J-59D01*
G03Y1648898I672J-2202D01*
G02X967206Y1648457I-117J-382D01*
G03X967202Y1648398I396J-56D01*
G01Y1646617D01*
X967356Y1646463D01*
X964448Y1643555D01*
Y1641902D01*
G02X964040Y1641502I-400J0D01*
G03X961701Y1639091I-40J-2302D01*
G02X961242Y1638676I-400J-19D01*
G03X959550Y1634536I-341J-2276D01*
G02X959598Y1633929I-235J-324D01*
G01X952985Y1627315D01*
G02X952355Y1627398I-283J282D01*
G03X948802Y1623845I-2255J-1298D01*
G02X948886Y1623215I-199J-347D01*
G01X926716Y1601042D01*
X926714D01*
X926712Y1601040D01*
X335099D01*
X330149Y1596089D01*
X166829D01*
G02X166678Y1596859I1J400D01*
G01X710591Y1820064D01*
X710671Y1820026D01*
G03X713428Y1823573I981J2083D01*
G02X713444Y1823845I154J127D01*
G03X709658Y1826214I-1596J1659D01*
G37*
G36*
G01X5499Y1192999D02*
X6500Y1194000D01*
X23000D01*
X27000Y1198000D01*
Y1204500D01*
X22500Y1209000D01*
X7999D01*
X5499Y1211500D01*
Y1245298D01*
G02X6155Y1245605I400J0D01*
G03Y1254433I3688J4414D01*
G02X5499Y1254740I-256J307D01*
G01Y1332675D01*
G02X6155Y1332982I400J0D01*
G03Y1341810I3688J4414D01*
G02X5499Y1342117I-256J307D01*
G01Y1350050D01*
X6999Y1351550D01*
X18747D01*
X18789Y1351406D01*
G03X20010Y1349972I2210J645D01*
G01Y1322628D01*
G03X22988Y1321708I989J-2078D01*
G01Y1350892D01*
G03X21899Y1354169I-1989J1158D01*
G01Y1393950D01*
X26799Y1398850D01*
Y1404650D01*
X21899Y1409550D01*
Y1520258D01*
G02X22582Y1520541I400J0D01*
G01X22800Y1520322D01*
X25485D01*
X25528Y1520279D01*
Y1496565D01*
X28010Y1494083D01*
Y1493269D01*
X25758Y1491017D01*
Y1489266D01*
X24102Y1487610D01*
Y1461283D01*
X24022Y1461123D01*
Y1460829D01*
X24011Y1460683D01*
X23962Y1460095D01*
X23948Y1459944D01*
Y1456963D01*
X24110Y1456801D01*
Y1447385D01*
X27329Y1444166D01*
X28094D01*
X34298Y1437962D01*
Y1435295D01*
G02X33646Y1434985I-400J1D01*
G01X31961Y1436353D01*
X31959Y1436351D01*
X31802Y1436459D01*
G03X28908Y1432874I-1302J-1909D01*
G01X29037Y1432751D01*
X29035Y1432749D01*
X31744Y1430549D01*
X31746Y1430551D01*
X31903Y1430443D01*
G03X34263Y1430296I1303J1909D01*
G02X34846Y1429941I183J-356D01*
G01Y1413290D01*
G02X34150Y1413021I-400J1D01*
G03X32589Y1413766I-1699J-1553D01*
G01X32514Y1413770D01*
X32506Y1413778D01*
X29052Y1413861D01*
Y1413851D01*
G03X28763Y1409260I-52J-2301D01*
G01X28942Y1409242D01*
Y1409240D01*
X32398Y1409157D01*
Y1409167D01*
G03X34150Y1409915I53J2301D01*
G02X34846Y1409646I296J-270D01*
G01Y1390163D01*
X34513D01*
X34488Y1390221D01*
G03X33933Y1391052I-2155J-838D01*
G01X33932D01*
G03X33924Y1391060I-1638J-1630D01*
G01Y1391062D01*
G03X33257Y1391503I-1590J-1680D01*
G01X33261Y1391512D01*
X30946Y1392519D01*
G02X31039Y1393262I186J354D01*
G03X28738Y1394019I-539J2238D01*
G02X28472Y1393363I-306J-258D01*
G03X27554Y1388940I27J-2312D01*
G01X27571Y1388923D01*
Y1388922D01*
X27574Y1388920D01*
X31409Y1387252D01*
X31413Y1387261D01*
G03X34151Y1387954I920J2122D01*
G02X34846Y1387684I295J-271D01*
G01Y1061236D01*
X34844Y1061235D01*
Y1039395D01*
X35401Y1038839D01*
Y1037170D01*
G02X34768Y1036844I-400J-1D01*
G03Y1022200I-5236J-7322D01*
G02X35401Y1021874I233J-325D01*
G01Y1020607D01*
X30222Y1015428D01*
Y1004427D01*
X33180Y1001468D01*
Y870175D01*
X26851Y863846D01*
X26763Y863850D01*
G03X25916Y863728I-101J-2300D01*
G02X25418Y863950I-130J378D01*
G03X21444Y861687I-2119J-900D01*
G02X21122Y861050I-322J-237D01*
G01X7499D01*
X5499Y863050D01*
Y870495D01*
G02X6155Y870802I400J0D01*
G03Y879630I3688J4414D01*
G02X5499Y879937I-256J307D01*
G01Y1095059D01*
G02X5979Y1095451I400J0D01*
G03X7543Y1100384I521J2549D01*
G02Y1101116I161J366D01*
G03X5979Y1106049I-1043J2384D01*
G02X5499Y1106441I-80J392D01*
G01Y1107059D01*
G02X5979Y1107451I400J0D01*
G03Y1112549I521J2549D01*
G02X5499Y1112941I-80J392D01*
G01Y1113559D01*
G02X5979Y1113951I400J0D01*
G03Y1119049I521J2549D01*
G02X5499Y1119441I-80J392D01*
G01Y1132699D01*
G02X6155Y1133006I400J0D01*
G03Y1141834I3688J4414D01*
G02X5499Y1142141I-256J307D01*
G01Y1192999D01*
G37*
G36*
G01X36398Y1499486D02*
G02X35717Y1499200I-400J-1D01*
G03X34099Y1499862I-1619J-1649D01*
G01X30499D01*
G03X29142Y1499421I1J-2312D01*
G02X28508Y1499745I-234J324D01*
G01Y1509472D01*
G02X29086Y1509830I400J0D01*
G03X30219Y1509591I1028J2070D01*
G01X33615Y1509742D01*
G03X35802Y1511736I-103J2309D01*
G01X35807Y1511775D01*
G03X33409Y1514360I-2295J276D01*
G01X30012Y1514209D01*
G03X29086Y1513970I102J-2309D01*
G02X28508Y1514328I-178J358D01*
G01Y1521513D01*
X26719Y1523302D01*
X26493D01*
Y1523509D01*
X26494Y1523517D01*
G03X22447Y1525193I-2295J183D01*
G01X22442Y1525187D01*
X22295Y1525040D01*
X22030Y1525305D01*
X21946Y1525431D01*
X21916Y1525504D01*
X21900Y1525581D01*
Y1682317D01*
X21899Y1682318D01*
Y1696850D01*
X15799Y1702950D01*
X15512D01*
X15479Y1703110D01*
G03X5509Y1705744I-5636J-1147D01*
G02X4808Y1706007I-301J263D01*
G01Y1742825D01*
G02X5509Y1743088I400J0D01*
G03Y1750650I4334J3781D01*
G02X4808Y1750913I-301J263D01*
G01Y1755659D01*
X5099Y1755950D01*
X17250D01*
X18000Y1755200D01*
Y1720900D01*
X36296Y1702604D01*
Y1606246D01*
X34998Y1604947D01*
Y1604830D01*
X34401Y1604234D01*
Y1602872D01*
G02X33942Y1602476I-400J0D01*
G03X33170Y1597938I-343J-2276D01*
G02X33318Y1597213I-74J-393D01*
G03X34598Y1592998I1281J-1913D01*
G02X34997Y1592598I-1J-400D01*
G01Y1591591D01*
X33054Y1589648D01*
Y1573706D01*
G02X32339Y1573460I-400J0D01*
G03X30605Y1574349I-1818J-1411D01*
G01X30604D01*
X27245Y1574504D01*
X27244D01*
G03X27033Y1569905I-122J-2299D01*
G01X27034D01*
X30398Y1569750D01*
X30399D01*
G03X32339Y1570638I121J2299D01*
G02X33054Y1570392I315J-246D01*
G01Y1563631D01*
G02X32676Y1563231I-400J-1D01*
G03X32415Y1563115I21J-399D01*
G01X30777Y1561478D01*
Y1560975D01*
X29744Y1559942D01*
Y1553595D01*
X30777Y1552562D01*
Y1548529D01*
G03X31177Y1548129I400J0D01*
G02X32046Y1547958I-2J-2302D01*
G01Y1547732D01*
G02X31431Y1547394I-400J0D01*
G03X29079Y1543439I-1232J-1944D01*
G02X29259Y1542949I-195J-350D01*
G03X29233Y1542808I374J-142D01*
G01Y1539651D01*
X27625Y1538043D01*
Y1537446D01*
G02X27148Y1537054I-400J0D01*
G03X27191Y1532545I-443J-2259D01*
G02X27425Y1532406I42J-196D01*
G03X31933Y1533049I2206J657D01*
G02X32130Y1533248I200J-1D01*
G03X32455Y1533276I-35J2302D01*
G01X32611Y1533300D01*
X32743Y1532978D01*
X32758Y1532902D01*
Y1526650D01*
X36398Y1523011D01*
Y1499486D01*
G37*
G36*
G01X22400Y693700D02*
X21500Y694600D01*
Y753051D01*
X28615Y760166D01*
G02X29297Y759883I282J-283D01*
G01Y746886D01*
X27984Y745573D01*
Y703033D01*
X30398Y700620D01*
Y694083D01*
X30015Y693700D01*
X22400D01*
G37*
G36*
G01X95372Y832979D02*
G02X94689Y833262I-283J283D01*
G01Y837917D01*
X89950Y842656D01*
Y845950D01*
X80000Y855900D01*
X75716D01*
G03X75709Y855905I-1337J-1864D01*
G01Y972653D01*
X89402Y986345D01*
Y988302D01*
X90500Y989401D01*
Y990848D01*
X90644Y990890D01*
G03X92288Y993355I-644J2210D01*
G02X92673Y993799I397J44D01*
G03X94089Y997855I-73J2301D01*
G01Y1154922D01*
G02X94772Y1155205I400J0D01*
G01X142510Y1107467D01*
Y1075117D01*
X140383Y1072990D01*
X124883D01*
X120510Y1068617D01*
Y1062617D01*
X110210Y1052317D01*
Y981580D01*
X98410Y969780D01*
Y967230D01*
X98274Y967184D01*
G03X96700Y964899I726J-2185D01*
G01X96704Y964811D01*
X91510Y959617D01*
Y919383D01*
X102212Y908681D01*
Y843700D01*
X100722D01*
G03X96421Y842926I-2022J-1100D01*
G01X96412Y842860D01*
X96022Y842470D01*
G03X96063Y841868I282J-283D01*
G02X96970Y839853I-1388J-1836D01*
G01X96963Y839761D01*
X99960Y836764D01*
Y835706D01*
G02X99330Y835379I-400J0D01*
G03X96996Y835572I-1330J-1879D01*
G03X96613Y835390I-46J-398D01*
G02X96534Y835275I-1936J1245D01*
G03X96152Y834873I1466J-1775D01*
G01X96139Y834855D01*
X96102Y834823D01*
Y834804D01*
X96070Y834754D01*
G03X95700Y833399I1930J-1255D01*
G01X95704Y833311D01*
X95372Y832979D01*
G37*
G36*
G01X34725Y1004137D02*
X33200Y1005661D01*
Y1014194D01*
X34718Y1015712D01*
G02X35401Y1015429I283J-283D01*
G01Y1011366D01*
X35408Y1011360D01*
Y1004420D01*
G02X34725Y1004137I-400J0D01*
G37*
G36*
G01X75510Y1198305D02*
G03X75647Y1194687I1489J-1755D01*
G02X75695Y1194080I-234J-324D01*
G01X73234Y1191619D01*
Y1191618D01*
X73072Y1191456D01*
Y1187572D01*
X71500Y1186000D01*
Y1059900D01*
X64452D01*
Y1229395D01*
X64453Y1229443D01*
X64471Y1229520D01*
X64487Y1229555D01*
G02X65016Y1229755I364J-164D01*
G03X66748Y1229382I1731J3828D01*
G01X71048D01*
G03X74756Y1231608I0J4201D01*
G02X75510Y1231420I354J-187D01*
G01Y1198305D01*
G37*
G36*
G01X75584Y1261166D02*
Y1354173D01*
G02X76267Y1354456I400J0D01*
G01X76625Y1354098D01*
X77455D01*
X77864Y1353689D01*
Y1353111D01*
X77352Y1352599D01*
Y1328135D01*
X85348Y1320139D01*
Y1252368D01*
G02X84666Y1252085I-400J0D01*
G01X75584Y1261166D01*
G37*
G36*
G01X91128Y1326772D02*
G02X90446Y1326489I-400J0D01*
G01X83882Y1333053D01*
Y1348372D01*
X93878Y1358368D01*
G02X94560Y1358085I282J-283D01*
G01Y1340567D01*
X91128Y1337135D01*
Y1326772D01*
G37*
G36*
G01X94502Y1365025D02*
Y1373543D01*
G02X94902Y1373554I200J0D01*
G01X94921Y1373213D01*
G03X99534Y1373161I2308J125D01*
G01X99548Y1373345D01*
X99541Y1373346D01*
G03X99537Y1373462I-2312J-22D01*
G01X99308Y1377742D01*
X99304Y1377785D01*
G03X95212Y1379065I-2304J-185D01*
G02X94502Y1379319I-310J253D01*
G01Y1384730D01*
X96940Y1387168D01*
Y1405065D01*
X96942Y1405066D01*
Y1406574D01*
G02X97624Y1406857I400J0D01*
G01X101608Y1402873D01*
Y1371165D01*
X95185Y1364742D01*
G02X94502Y1365025I-283J283D01*
G37*
G36*
G01X62674Y1409582D02*
Y1418242D01*
G02X63357Y1418525I400J0D01*
G01X70187Y1411695D01*
G02X69904Y1411012I-283J-283D01*
G01X66748D01*
G03X63394Y1409341I0J-4202D01*
G02X62674Y1409582I-320J241D01*
G37*
G36*
G01X78035Y1435772D02*
X76914Y1436892D01*
Y1486488D01*
X75800Y1487601D01*
Y1543191D01*
G02X76483Y1543474I400J0D01*
G01X78718Y1541240D01*
Y1436055D01*
G02X78035Y1435772I-400J0D01*
G37*
G36*
G01X36620Y1440819D02*
G02X35938Y1440536I-400J0D01*
G01X30865Y1445609D01*
G02X31130Y1446291I283J283D01*
G01X31272Y1446297D01*
X31309Y1446284D01*
G03X32534Y1450708I784J2164D01*
G02X32211Y1451118I76J392D01*
G03X32094Y1451418I-400J17D01*
G01X27703Y1455808D01*
G03X27455Y1455924I-283J-283D01*
G02X27090Y1456322I35J398D01*
G01Y1458035D01*
X26928Y1458197D01*
Y1459812D01*
X26930Y1459841D01*
X26985Y1460500D01*
X27082Y1460835D01*
Y1486376D01*
X28738Y1488032D01*
Y1489783D01*
X30990Y1492035D01*
Y1495238D01*
X34099D01*
G03X35717Y1495900I-1J2311D01*
G02X36397Y1495614I280J-286D01*
G01Y1483908D01*
G02X35771Y1483579I-400J0D01*
G03X33835Y1483897I-1306J-1896D01*
G01X33798Y1483887D01*
X32112Y1484065D01*
X32078Y1484083D01*
G03X31628Y1479836I-1079J-2033D01*
G01X31666Y1479846D01*
X33352Y1479668D01*
X33386Y1479650D01*
G03X35771Y1479787I1080J2033D01*
G02X36398Y1479458I227J-329D01*
G01Y1472571D01*
X38436Y1470533D01*
Y1448423D01*
X36620Y1446608D01*
Y1440819D01*
G37*
G36*
G01X71048Y1402610D02*
G03X71216Y1402613I9J4201D01*
G01X71303Y1402616D01*
X71507Y1402413D01*
X63357Y1394264D01*
G02X62674Y1394547I-283J283D01*
G01Y1404040D01*
G02X63394Y1404281I400J0D01*
G03X66748Y1402610I3354J2531D01*
G01X71048D01*
G37*
G36*
G01X141081Y1334633D02*
X134100Y1341613D01*
Y1354513D01*
X131033Y1357581D01*
X131019Y1357606D01*
G03X129788Y1358663I-2019J-1106D01*
G02X129642Y1359322I137J376D01*
G01X131119Y1360798D01*
X137381D01*
X138798Y1359381D01*
Y1338930D01*
X142615Y1335113D01*
G02X142535Y1334485I-283J-283D01*
G03X142169Y1334219I1164J-1986D01*
G02X141621Y1334234I-266J299D01*
G03X141106Y1334619I-1622J-1633D01*
G01X141081Y1334633D01*
G37*
G36*
G01X144202Y1361619D02*
X141505Y1364316D01*
G02X141788Y1364998I283J282D01*
G01X144888D01*
X148422Y1361464D01*
Y1337913D01*
G02X147740Y1337630I-400J0D01*
G01X144202Y1341168D01*
Y1361619D01*
G37*
G36*
G01X97422Y1311829D02*
G02X96740Y1312112I-282J283D01*
G01Y1335233D01*
X99490Y1337983D01*
Y1362075D01*
X102928Y1365513D01*
G02X103610Y1365230I282J-283D01*
G01Y1350725D01*
G02X103084Y1350346I-400J0D01*
G03X100038Y1348154I-734J-2192D01*
G01Y1344500D01*
G03X103084Y1342308I2312J0D01*
G02X103610Y1341929I126J-379D01*
G01Y1324380D01*
X102889Y1323659D01*
X102801Y1323663D01*
G03X105000Y1321464I-101J-2300D01*
G01X104996Y1321552D01*
X106590Y1323146D01*
Y1331785D01*
G02X107320Y1332011I400J0D01*
G03X111533Y1333139I1908J1304D01*
G01X111540Y1333227D01*
Y1337100D01*
G03X107320Y1338394I-2311J-10D01*
G02X106590Y1338620I-330J226D01*
G01Y1364983D01*
X109490Y1367883D01*
Y1402438D01*
G02X110172Y1402721I400J0D01*
G01X113910Y1398983D01*
Y1365083D01*
X115810Y1363183D01*
Y1350078D01*
G02X115129Y1349794I-400J0D01*
G03X111188Y1348154I-1629J-1640D01*
G01Y1344500D01*
G03X115129Y1342860I2312J0D01*
G02X115810Y1342576I281J-284D01*
G01Y1341217D01*
X112710Y1338117D01*
Y1327117D01*
X97422Y1311829D01*
G37*
G36*
G01X338562Y1581590D02*
G02X338279Y1582272I0J400D01*
G01X341517Y1585510D01*
X348220D01*
G02X348450Y1584783I0J-400D01*
G03X347607Y1582124I1324J-1883D01*
G02X347230Y1581590I-377J-134D01*
G01X338562D01*
G37*
%LPC*%
G75*
G36*
G01X107087Y1739497D02*
X107081Y1739606D01*
X107077D01*
X107178Y1743608D01*
X107180Y1743610D01*
X107181D01*
X107187Y1743617D01*
X107189Y1743640D01*
G02X111809Y1743653I2310J-90D01*
G01X111810Y1743643D01*
Y1743634D01*
G02X111811Y1743560I-2311J-68D01*
G01X111812D01*
Y1743558D01*
X111810D01*
Y1743552D01*
X111812D01*
Y1743550D01*
X111811D01*
Y1743494D01*
X111821D01*
X111722Y1739558D01*
Y1739552D01*
X111720Y1739490D01*
X111717D01*
X111704Y1739373D01*
G02X107087Y1739497I-2305J177D01*
G37*
G36*
G01X880366Y1456460D02*
Y1456452D01*
G02Y1456402I-2312J-25D01*
G01Y1456362D01*
X880363Y1456327D01*
G02X879598Y1454729I-2309J123D01*
G02X876189Y1455084I-1544J1720D01*
G02X875757Y1456186I1865J1367D01*
G01X875739Y1456317D01*
X875736Y1456316D01*
X875534Y1459862D01*
X875539Y1459863D01*
X875541Y1459974D01*
G02X880161Y1460124I2312J17D01*
G01X880171Y1460125D01*
X880179Y1459998D01*
X880168D01*
Y1459994D01*
X880178D01*
X880373Y1456581D01*
X880370Y1456578D01*
X880369D01*
X880364Y1456574D01*
Y1456545D01*
G02X880366Y1456460I-2310J-97D01*
G37*
G36*
G01X226800Y1090698D02*
X225619D01*
X181519Y1046598D01*
X151300D01*
G02Y1052002I0J2702D01*
G01X179281D01*
X223381Y1096102D01*
X226800D01*
G02Y1090698I0J-2702D01*
G37*
G36*
G01X135003Y1979810D02*
G03X135696Y1979783I354J186D01*
G02X135597Y1977190I2204J-1383D01*
G03X134904Y1977217I-354J-186D01*
G02X135003Y1979810I-2204J1383D01*
G37*
G36*
G01X774074Y1973765D02*
G03X773541Y1973767I-268J-298D01*
G02X773554Y1977647I-1727J1946D01*
G03X774087Y1977645I268J298D01*
G02X774074Y1973765I1727J-1946D01*
G37*
G36*
G01X135003Y1973610D02*
G03X135696Y1973583I354J186D01*
G02X135597Y1970990I2204J-1383D01*
G03X134904Y1971017I-354J-186D01*
G02X135003Y1973610I-2204J1383D01*
G37*
G36*
G01X782091Y1969163D02*
G03Y1969763I-264J300D01*
G02X781964Y1973542I1723J1950D01*
G03X781991Y1974075I-285J282D01*
G02X785866Y1973879I2025J1633D01*
G03X785839Y1973346I285J-282D01*
G02X785537Y1969763I-2025J-1634D01*
G03Y1969163I264J-300D01*
G02X782091I-1723J-1950D01*
G37*
G36*
G01X291449Y1972773D02*
G03X292049I300J264D01*
G02X295722Y1969100I1950J-1723D01*
G03Y1968500I264J-300D01*
G02Y1964600I-1723J-1950D01*
G03Y1964000I264J-300D01*
G02X292237Y1960135I-1723J-1950D01*
G03X291638Y1960068I-270J-295D01*
G02X288059Y1963717I-2139J1482D01*
G03Y1964383I-222J333D01*
G02X287776Y1968500I1440J2167D01*
G03Y1969100I-264J300D01*
G02X291449Y1972773I1723J1950D01*
G37*
G36*
G01X307630Y1964006D02*
G03X307697Y1963473I327J-230D01*
G02X303870Y1962994I-1697J-1973D01*
G03X303803Y1963527I-327J230D01*
G02X307630Y1964006I1697J1973D01*
G37*
G36*
G01X287286Y1946233D02*
G03X286736Y1946181I-248J-314D01*
G02X286422Y1949500I-1737J1510D01*
G03X286972Y1949552I248J314D01*
G02X287286Y1946233I1737J-1510D01*
G37*
G36*
G01X333554Y1946346D02*
G03X333515Y1946077I126J-156D01*
G02X330171Y1946554I-1893J-1310D01*
G03X330210Y1946823I-126J156D01*
G02X333554Y1946346I1893J1310D01*
G37*
G36*
G01X344371Y1945560D02*
G03X344315Y1944968I238J-321D01*
G02X341249Y1945258I-1694J-1559D01*
G03X341305Y1945850I-238J321D01*
G02X344371Y1945560I1694J1559D01*
G37*
G36*
G01X96788Y1942526D02*
G03X96863Y1943064I-253J310D01*
G02X100936Y1946287I2136J1486D01*
G03X101527Y1946282I298J267D01*
G02X104850Y1942328I1906J-1772D01*
G03X104717Y1941801I218J-335D01*
G02X100721Y1938595I-2284J-1246D01*
G03X100188Y1938589I-263J-301D01*
G02X96788Y1942526I-1755J1921D01*
G37*
G36*
G01X773144Y1938440D02*
G03Y1938160I143J-140D01*
G02X769854I-1645J-1610D01*
G03Y1938440I-143J140D01*
G02X773144I1645J1610D01*
G37*
G36*
G01X296360Y1931068D02*
G03X295761Y1931135I-329J-228D01*
G02X296138Y1934532I-1762J1915D01*
G03X296737Y1934465I329J228D01*
G02X300233Y1934490I1762J-1915D01*
G03X300765I266J299D01*
G02X304449Y1934273I1734J-1940D01*
G03X305049I300J264D01*
G02Y1930827I1950J-1723D01*
G03X304449I-300J-264D01*
G02X300765Y1930610I-1950J1723D01*
G03X300233I-266J-299D01*
G02X296360Y1931068I-1734J1940D01*
G37*
G36*
G01X25133Y1920322D02*
G03X24580Y1920336I-284J-282D01*
G02X24662Y1923661I-1550J1702D01*
G03X25215Y1923647I284J282D01*
G02X25133Y1920322I1550J-1702D01*
G37*
G36*
G01X280559Y1925717D02*
G03Y1926383I-222J333D01*
G02X282972Y1930963I1441J2167D01*
G03X283474Y1931144I150J371D01*
G02X284894Y1927829I2025J-1094D01*
G03X284418Y1927590I-104J-386D01*
G02X283439Y1926383I-2418J961D01*
G03Y1925717I222J-333D01*
G02Y1921383I-1440J-2167D01*
G03Y1920717I222J-333D01*
G02X280559I-1440J-2167D01*
G03Y1921383I-222J333D01*
G02Y1925717I1440J2167D01*
G37*
G36*
G01X268722Y1918100D02*
G03Y1917500I264J-300D01*
G02X265276I-1723J-1950D01*
G03Y1918100I-264J300D01*
G02Y1922000I1723J1950D01*
G03Y1922600I-264J300D01*
G02Y1926500I1723J1950D01*
G03Y1927100I-264J300D01*
G02Y1931000I1723J1950D01*
G03Y1931600I-264J300D01*
G02X268722I1723J1950D01*
G03Y1931000I264J-300D01*
G02Y1927100I-1723J-1950D01*
G03Y1926500I264J-300D01*
G02Y1922600I-1723J-1950D01*
G03Y1922000I264J-300D01*
G02Y1918100I-1723J-1950D01*
G37*
G36*
G01X809659Y1912915D02*
G03Y1912315I264J-300D01*
G02X806213I-1723J-1950D01*
G03Y1912915I-264J300D01*
G02X806026Y1916632I1723J1950D01*
G03X806035Y1917165I-294J272D01*
G02X806061Y1920595I1970J1700D01*
G03X806060Y1921128I-299J266D01*
G02X809941Y1921135I1937J1737D01*
G03X809942Y1920602I299J-266D01*
G02X809915Y1917098I-1937J-1737D01*
G03X809906Y1916565I294J-272D01*
G02X809659Y1912915I-1970J-1700D01*
G37*
G36*
G01X793556Y1915433D02*
G03X793557Y1915966I-298J267D01*
G02X793709Y1919582I1944J1729D01*
G03X793708Y1920162I-276J290D01*
G02X797291Y1920164I1790J1888D01*
G03X797292Y1919584I276J-290D01*
G02X797438Y1915959I-1791J-1888D01*
G03X797437Y1915426I298J-267D01*
G02X797448Y1911978I-1944J-1730D01*
G03X797452Y1911446I300J-264D01*
G02X793571Y1911414I-1926J-1750D01*
G03X793567Y1911946I-300J264D01*
G02X793556Y1915433I1926J1750D01*
G37*
G36*
G01X131994Y1911381D02*
G03X132194Y1910861I368J-157D01*
G02X128706Y1909519I-1094J-2361D01*
G03X128506Y1910039I-368J157D01*
G02X127552Y1910796I1095J2360D01*
G03X126939Y1910815I-314J-247D01*
G02X126644Y1910534I-1937J1738D01*
G03X126569Y1909996I253J-310D01*
G02X122788Y1910526I-2136J-1486D01*
G03X122863Y1911064I-253J310D01*
G02X127047Y1914154I2136J1486D01*
G03X127660Y1914135I314J247D01*
G02X131994Y1911381I1940J-1734D01*
G37*
G36*
G01X76833Y1897492D02*
G03X76757Y1898019I-333J221D01*
G02X76788Y1902026I1676J1991D01*
G03X76863Y1902564I-253J310D01*
G02X80936Y1905787I2136J1486D01*
G03X81527Y1905782I298J267D01*
G02X85599Y1902568I1907J-1771D01*
G03X85675Y1902041I333J-221D01*
G02X85696Y1898077I-1676J-1991D01*
G03X85629Y1897544I260J-303D01*
G02X84981Y1893911I-2130J-1494D01*
G03X84914Y1893312I228J-329D01*
G02X84939Y1889816I-1915J-1762D01*
G03Y1889284I299J-266D01*
G02X81265Y1885610I-1940J-1734D01*
G03X80733I-266J-299D01*
G02X77059Y1889284I-1734J1940D01*
G03Y1889816I-299J266D01*
G02X77276Y1893500I1940J1734D01*
G03Y1894100I-264J300D01*
G02X76833Y1897492I1723J1950D01*
G37*
G36*
G01X229943Y1885740D02*
G03X229353Y1885801I-323J-237D01*
G02X229671Y1888873I-1539J1712D01*
G03X230261Y1888812I323J237D01*
G02X229943Y1885740I1539J-1712D01*
G37*
G36*
G01X855810Y1871046D02*
Y1870948D01*
X855804Y1870860D01*
G02X853485Y1868725I-2305J176D01*
G01X850085Y1868745D01*
G02X850113Y1873367I14J2311D01*
G01X853512Y1873347D01*
G02X855810Y1871046I-13J-2311D01*
G37*
G36*
G01X121082Y1870816D02*
X121079Y1870993D01*
X121075Y1870994D01*
X121275Y1874392D01*
X121277Y1874391D01*
X121304Y1874581D01*
G02X125903Y1874297I2288J-328D01*
G01X125906Y1874120D01*
X125910Y1874119D01*
X125719Y1870868D01*
X125710Y1870723D01*
X125701Y1870714D01*
X125694Y1870642D01*
G02X121082Y1870816I-2301J218D01*
G37*
G36*
G01X869226Y1865625D02*
Y1861752D01*
X869219Y1861664D01*
G02X864602Y1861840I-2305J176D01*
G01Y1865615D01*
G02X869226Y1865625I2312J0D01*
G37*
G36*
G01X140310Y1865161D02*
Y1861409D01*
X140304Y1861321D01*
G02X135688Y1861497I-2305J176D01*
G01Y1865151D01*
G02X140310Y1865161I2311J0D01*
G37*
G36*
G01X805299Y1824144D02*
G03X805579Y1824111I157J124D01*
G02X805201Y1820864I1421J-1811D01*
G03X804921Y1820897I-157J-124D01*
G02X805299Y1824144I-1421J1811D01*
G37*
G36*
G01X643642Y1816423D02*
G03X643466Y1817016I-331J224D01*
G02X646267Y1817848I894J2121D01*
G03X646443Y1817255I331J-224D01*
G02X643642Y1816423I-894J-2121D01*
G37*
G36*
G01X795489Y1803226D02*
G03X795261Y1803067I-32J-197D01*
G02X793360Y1805774I-2261J433D01*
G03X793588Y1805933I32J197D01*
G02X795489Y1803226I2261J-433D01*
G37*
G36*
G01X163265Y1791498D02*
X163199D01*
X163149Y1791466D01*
G02X160794Y1795419I-1249J1934D01*
G01X160819Y1795433D01*
X161288Y1795902D01*
X181839D01*
X215148Y1829211D01*
Y1886562D01*
X216067Y1887481D01*
X216081Y1887506D01*
G02X219552Y1884613I2019J-1107D01*
G01Y1871481D01*
G03X220234Y1871198I400J0D01*
G01X226938Y1877902D01*
X229127D01*
X229154Y1877910D01*
G02Y1873490I646J-2210D01*
G01X229127Y1873498D01*
X228762D01*
X222752Y1867488D01*
Y1825673D01*
X185177Y1788098D01*
X165188D01*
X164819Y1788467D01*
X164794Y1788481D01*
G02X163655Y1791010I1106J2019D01*
G03X163265Y1791498I-390J88D01*
G37*
G36*
G01X820498Y1870427D02*
X820490Y1870454D01*
G02X824910I2210J646D01*
G01X824902Y1870427D01*
Y1844212D01*
X880781Y1788333D01*
X880806Y1788319D01*
G02X881191Y1784546I-1106J-2019D01*
G03X881185Y1783941I259J-305D01*
G02X879018Y1780003I-1521J-1728D01*
G01X878991Y1780012D01*
X878349D01*
X813298Y1845062D01*
Y1880622D01*
G03X812603Y1880891I-400J-1D01*
G02X809866Y1884497I-1703J1549D01*
G03X809970Y1885137I-179J358D01*
G01X809748Y1885358D01*
X806573D01*
X806546Y1885350D01*
G02Y1889770I-646J2210D01*
G01X806573Y1889762D01*
X811572D01*
X817702Y1883632D01*
Y1846886D01*
X819816Y1844772D01*
G03X820498Y1845055I282J283D01*
G01Y1870427D01*
G37*
G36*
G01X82885Y1748948D02*
X83032Y1752344D01*
G02X87652Y1752255I2309J-98D01*
G01Y1752245D01*
X87653D01*
G02Y1752238I-2312J-4D01*
G01X87652Y1752237D01*
Y1752191D01*
X87502Y1748717D01*
X87499Y1748672D01*
G02X82885Y1748948I-2305J176D01*
G37*
G36*
G01X884196Y1746470D02*
G03X884755Y1746416I307J256D01*
G02X884404Y1742730I1645J-2016D01*
G03X883845Y1742784I-307J-256D01*
G02X884196Y1746470I-1645J2016D01*
G37*
G36*
G01X133110Y1731900D02*
G03X132777Y1731307I17J-400D01*
G02X128525Y1731746I-2278J-1257D01*
G03X128192Y1732405I-303J260D01*
G02X130309Y1736200I-192J2595D01*
G03X130975Y1736134I355J185D01*
G02X133110Y1731900I2025J-1634D01*
G37*
G36*
G01X141924Y1731445D02*
G03X142590Y1731318I373J145D01*
G02X142075Y1728605I1909J-1768D01*
G03X141409Y1728732I-373J-145D01*
G02X141924Y1731445I-1909J1768D01*
G37*
G36*
G01X107724Y1710747D02*
G03X107440Y1710771I-154J-128D01*
G02X107926Y1714174I-1691J1978D01*
G03X108206Y1714118I167J109D01*
G02X107724Y1710747I1293J-1905D01*
G37*
G36*
G01X133936Y1708460D02*
G03X133656Y1708452I-136J-147D01*
G02X133562Y1711740I-1657J1598D01*
G03X133842Y1711748I136J147D01*
G02X133936Y1708460I1657J-1598D01*
G37*
G36*
G01X153298Y1715471D02*
Y1769865D01*
X98792Y1824371D01*
G03X98227I-282J-283D01*
G02X94390Y1825357I-1627J1629D01*
G03X93931Y1825639I-384J-111D01*
G02X91890Y1826255I-431J2261D01*
G03X91610I-140J-143D01*
G02X87790Y1828546I-1610J1645D01*
G01X87798Y1828573D01*
Y1829838D01*
X91962Y1834002D01*
X99915D01*
X160902Y1773015D01*
Y1728658D01*
G03X161594Y1728386I400J1D01*
G02X162813Y1729123I1904J-1773D01*
G03X163079Y1729656I-106J386D01*
G02X167542Y1732225I2420J958D01*
G03X168208Y1732283I314J248D01*
G02X172755Y1729753I2291J-1233D01*
G03X173021Y1729162I347J-199D01*
G02X170549Y1724890I-522J-2549D01*
G03X169949I-300J-264D01*
G02X166049I-1950J1723D01*
G03X165449I-300J-264D01*
G02X161594Y1724840I-1950J1723D01*
G03X160902Y1724568I-292J-273D01*
G01Y1716865D01*
G03X161461Y1716499I400J1D01*
G02X164666Y1715553I1038J-2386D01*
G03X165332I333J222D01*
G02X169684Y1715526I2167J-1440D01*
G03X170350Y1715517I336J217D01*
G02X175024Y1714679I2149J-1467D01*
G01X175037Y1714625D01*
X183301Y1706361D01*
Y1683373D01*
X183310Y1683346D01*
G02X183324Y1682105I-2210J-646D01*
G03X183710Y1681602I386J-103D01*
G01X305295D01*
X328983Y1705290D01*
X376145D01*
G02Y1702310I1755J-1490D01*
G01X330217D01*
X306529Y1678622D01*
X155323D01*
G03X154925Y1678185I0J-400D01*
G02X150878Y1676478I-2292J-218D01*
G01X147216D01*
X121368Y1702326D01*
X121352Y1702336D01*
G02X121013Y1705870I1290J1907D01*
G03Y1706435I-283J283D01*
G01X118910Y1708538D01*
Y1712158D01*
X115428Y1715640D01*
G03X114791Y1715543I-283J-283D01*
G02X111128Y1718243I-2038J1069D01*
G03X111099Y1718835I-283J283D01*
G02X114862Y1720512I1463J1778D01*
G01X114858Y1720424D01*
X122107Y1713174D01*
X122248Y1713295D01*
G02X123409Y1709273I1501J-1745D01*
G03X123067Y1708595I-59J-395D01*
G01X126647Y1705015D01*
G03X127199Y1705002I283J283D01*
G02X130378Y1701673I1550J-1702D01*
G03Y1701108I283J-283D01*
G01X130464Y1701022D01*
G03X131094Y1701105I283J282D01*
G02X135109Y1701065I1996J-1146D01*
G01X135123Y1701040D01*
X148161Y1688002D01*
X168427D01*
X168454Y1688010D01*
G02X168543Y1688034I644J-2211D01*
G03X168729Y1688705I-97J388D01*
G01X153298Y1704135D01*
Y1711629D01*
G03X152617Y1711913I-400J0D01*
G02Y1715187I-1618J1637D01*
G03X153298Y1715471I281J284D01*
G37*
G36*
G01X178163Y1628036D02*
G03X178088Y1628574I-328J228D01*
G02X178057Y1632581I1645J2016D01*
G03X178133Y1633108I-257J306D01*
G02X181975Y1632559I2166J1442D01*
G03X181899Y1632032I257J-306D01*
G02X181869Y1629104I-2166J-1442D01*
G03X181944Y1628566I328J-228D01*
G02X178163Y1628036I-1645J-2016D01*
G37*
G36*
G01X308859Y1567965D02*
G03X308268Y1567842I-242J-318D01*
G02X307753Y1571035I-2270J1272D01*
G03X308352Y1571104I269J296D01*
G02X308859Y1567965I1897J-1304D01*
G37*
G36*
G01X787550Y1563846D02*
G03Y1563246I264J-300D01*
G02X784104I-1723J-1950D01*
G03Y1563846I-264J300D01*
G02X783374Y1566665I1723J1950D01*
G03X782975Y1567198I-377J134D01*
G02X780877Y1568073I-148J2598D01*
G03X780277I-300J-264D01*
G02X776377I-1950J1723D01*
G03X775777I-300J-264D01*
G02X775524Y1567823I-1951J1722D01*
G03X775457Y1567290I260J-303D01*
G02X771630Y1567769I-2130J-1494D01*
G03X771697Y1568302I-260J303D01*
G02X775777Y1571519I2130J1494D01*
G03X776377I300J264D01*
G02X780277I1950J-1723D01*
G03X780877I300J264D01*
G02X785280Y1568927I1950J-1723D01*
G03X785679Y1568394I377J-134D01*
G02X787550Y1563846I148J-2598D01*
G37*
G36*
G01X280712Y1528452D02*
G03X280779Y1527923I329J-227D01*
G02X276930Y1527430I-1704J-1966D01*
G03X276863Y1527959I-329J227D01*
G02X280712Y1528452I1704J1966D01*
G37*
G36*
G01X269119Y1520643D02*
G03Y1520057I273J-293D01*
G02X265579I-1770J-1907D01*
G03Y1520643I-273J293D01*
G02X265688Y1524553I1770J1907D01*
G03Y1525169I-255J308D01*
G02X269010I1661J2003D01*
G03Y1524553I255J-308D01*
G02X269119Y1520643I-1661J-2003D01*
G37*
G36*
G01X281222Y1513100D02*
G03Y1512500I264J-300D01*
G02X277776I-1723J-1950D01*
G03Y1513100I-264J300D01*
G02X281222I1723J1950D01*
G37*
G36*
G01X797439Y1507383D02*
G03Y1506717I222J-333D01*
G02X794559I-1440J-2167D01*
G03Y1507383I-222J333D01*
G02X794276Y1511500I1440J2167D01*
G03Y1512100I-264J300D01*
G02Y1516000I1723J1950D01*
G03Y1516600I-264J300D01*
G02X797722I1723J1950D01*
G03Y1516000I264J-300D01*
G02Y1512100I-1723J-1950D01*
G03Y1511500I264J-300D01*
G02X797439Y1507383I-1723J-1950D01*
G37*
G36*
G01X807805Y1505889D02*
G03Y1506555I-222J333D01*
G02X807597Y1510736I1440J2167D01*
G03X807565Y1511379I-253J310D01*
G02X807790Y1515854I1434J2171D01*
G03X807823Y1516543I-186J354D01*
G02X810454Y1516418I1422J2179D01*
G03X810421Y1515729I186J-354D01*
G02X810647Y1511536I-1422J-2179D01*
G03X810679Y1510893I253J-310D01*
G02X810685Y1506555I-1434J-2171D01*
G03Y1505889I222J-333D01*
G02X807805I-1440J-2167D01*
G37*
G36*
G01X974053Y1500177D02*
G03X974073Y1499510I231J-327D01*
G02X971196Y1499423I-1373J-2210D01*
G03X971176Y1500090I-231J327D01*
G02X970826Y1504250I1373J2210D01*
G03Y1504850I-264J300D01*
G02X974272I1723J1950D01*
G03Y1504250I264J-300D01*
G02X974053Y1500177I-1723J-1950D01*
G37*
G36*
G01X961553Y1498177D02*
G03X961573Y1497510I231J-327D01*
G02X958696Y1497423I-1373J-2210D01*
G03X958676Y1498090I-231J327D01*
G02X958326Y1502250I1373J2210D01*
G03Y1502850I-264J300D01*
G02X961772I1723J1950D01*
G03Y1502250I264J-300D01*
G02X961553Y1498177I-1723J-1950D01*
G37*
G36*
G01X949996Y1497423D02*
G03X949976Y1498090I-231J327D01*
G02X949626Y1502250I1373J2210D01*
G03Y1502850I-264J300D01*
G02X953072I1723J1950D01*
G03Y1502250I264J-300D01*
G02X952853Y1498177I-1723J-1950D01*
G03X952873Y1497510I231J-327D01*
G02X949996Y1497423I-1373J-2210D01*
G37*
G36*
G01X854600Y1466356D02*
Y1466258D01*
X854593Y1466170D01*
G02X852250Y1464035I-2305J176D01*
G01X848851Y1464091D01*
G02X848926Y1468713I38J2311D01*
G01X852326Y1468657D01*
G02X854600Y1466356I-38J-2311D01*
G37*
G36*
G01X126314Y1468144D02*
X126295Y1468110D01*
X126018Y1465696D01*
X126028Y1465659D01*
G02X121784Y1466147I-2220J-609D01*
G01X121803Y1466181D01*
X122080Y1468594D01*
X122070Y1468632D01*
G02X126314Y1468144I2220J609D01*
G37*
G36*
G01X140700Y1456130D02*
X140682Y1456308D01*
X140679D01*
X140579Y1459938D01*
X140582D01*
X140592Y1460127D01*
G02X145199Y1460243I2308J-126D01*
G01X145217Y1460064D01*
X145221D01*
X145320Y1456436D01*
X145310Y1456427D01*
Y1456285D01*
X145304Y1456197D01*
G02X140700Y1456130I-2305J175D01*
G37*
G36*
G01X970317Y1464504D02*
G03X970290Y1465197I-213J339D01*
G02X972883Y1465296I1210J2303D01*
G03X972910Y1464603I213J-339D01*
G02X973423Y1460350I-1210J-2303D01*
G03Y1459750I264J-300D01*
G02X973140Y1455633I-1723J-1950D01*
G03Y1454967I222J-333D01*
G02X973423Y1450850I-1440J-2167D01*
G03Y1450250I264J-300D01*
G02X969977I-1723J-1950D01*
G03Y1450850I-264J300D01*
G02X970260Y1454967I1723J1950D01*
G03Y1455633I-222J333D01*
G02X969977Y1459750I1440J2167D01*
G03Y1460350I-264J300D01*
G02X970317Y1464504I1723J1950D01*
G37*
G36*
G01X951117D02*
G03X951090Y1465197I-213J339D01*
G02X953683Y1465296I1210J2303D01*
G03X953710Y1464603I213J-339D01*
G02X954223Y1460350I-1210J-2303D01*
G03Y1459750I264J-300D01*
G02X953940Y1455633I-1723J-1950D01*
G03Y1454967I222J-333D01*
G02X954223Y1450850I-1440J-2167D01*
G03Y1450250I264J-300D01*
G02X950777I-1723J-1950D01*
G03Y1450850I-264J300D01*
G02X951060Y1454967I1723J1950D01*
G03Y1455633I-222J333D01*
G02X950777Y1459750I1440J2167D01*
G03Y1460350I-264J300D01*
G02X951117Y1464504I1723J1950D01*
G37*
G36*
G01X960817Y1463504D02*
G03X960790Y1464197I-213J339D01*
G02X963383Y1464296I1210J2303D01*
G03X963410Y1463603I213J-339D01*
G02X963923Y1459350I-1210J-2303D01*
G03Y1458750I264J-300D01*
G02X963640Y1454633I-1723J-1950D01*
G03Y1453967I222J-333D01*
G02X963923Y1449850I-1440J-2167D01*
G03Y1449250I264J-300D01*
G02X960477I-1723J-1950D01*
G03Y1449850I-264J300D01*
G02X960760Y1453967I1723J1950D01*
G03Y1454633I-222J333D01*
G02X960477Y1458750I1440J2167D01*
G03Y1459350I-264J300D01*
G02X960817Y1463504I1723J1950D01*
G37*
G36*
G01X102624Y1440668D02*
X102688Y1444975D01*
G02X107310Y1444951I2311J-34D01*
G01Y1444941D01*
X107311Y1444940D01*
G02Y1444908I-2312J-16D01*
G01Y1444907D01*
X107246Y1440535D01*
X107240Y1440458D01*
G02X102624Y1440668I-2305J176D01*
G37*
G36*
G01X973723Y1440050D02*
G03Y1439450I264J-300D01*
G02X970277I-1723J-1950D01*
G03Y1440050I-264J300D01*
G02X973723I1723J1950D01*
G37*
G36*
G01X954523D02*
G03Y1439450I264J-300D01*
G02X951077I-1723J-1950D01*
G03Y1440050I-264J300D01*
G02X954523I1723J1950D01*
G37*
G36*
G01X964223Y1439050D02*
G03Y1438450I264J-300D01*
G02X960777I-1723J-1950D01*
G03Y1439050I-264J300D01*
G02X964223I1723J1950D01*
G37*
G36*
G01X119702Y1429986D02*
Y1426113D01*
X119695Y1426025D01*
G02X115078Y1426201I-2305J176D01*
G01Y1429976D01*
G02X119702Y1429986I2312J0D01*
G37*
G36*
G01X821100Y1483013D02*
Y1469435D01*
G03X821589Y1469045I400J0D01*
G02X824310Y1466154I511J-2245D01*
G01X824302Y1466127D01*
Y1425312D01*
X867790Y1381824D01*
G02X868715Y1380910I-1090J-2028D01*
G01X868728Y1380885D01*
X868902Y1380712D01*
Y1380469D01*
X868910Y1380442D01*
G02X868202Y1378052I-2210J-645D01*
G03X868187Y1377460I261J-303D01*
G02X865950Y1373586I-1591J-1664D01*
G01X865923Y1373594D01*
X865262D01*
X864228Y1374628D01*
G03X863635Y1374598I-283J-283D01*
G02X860397Y1377836I-1786J1452D01*
G03X860427Y1378429I-253J310D01*
G01X816698Y1422159D01*
Y1481189D01*
X813619Y1484267D01*
X813594Y1484281D01*
G02X816719Y1487406I1106J2019D01*
G01X816733Y1487381D01*
X821100Y1483013D01*
G37*
G36*
G01X200904Y1364390D02*
X205283D01*
X290010Y1449117D01*
Y1510117D01*
X292704Y1512811D01*
X292700Y1512899D01*
G02X294899Y1510700I2300J101D01*
G01X294811Y1510704D01*
X292990Y1508883D01*
Y1447883D01*
X206517Y1361410D01*
X200904D01*
G02Y1364390I-1755J1490D01*
G37*
G36*
G01X158585Y1311464D02*
X341307D01*
X341382Y1311540D01*
X343669D01*
G02Y1308560I1755J-1490D01*
G01X342616D01*
X342541Y1308486D01*
X182205D01*
G03X181911Y1307814I0J-400D01*
G02X181722Y1304100I-1912J-1765D01*
G03Y1303500I264J-300D01*
G02X181480Y1299410I-1723J-1950D01*
G03Y1298753I227J-328D01*
G02X181915Y1294852I-1481J-2140D01*
G03Y1294311I294J-270D01*
G02X178049Y1290827I-1916J-1761D01*
G03X177449I-300J-264D01*
G02X173937Y1294631I-1950J1723D01*
G03X173980Y1295233I-240J320D01*
G02X174280Y1299165I1843J1837D01*
G03X174237Y1299837I-237J322D01*
G02X173559Y1303847I1262J2276D01*
G03Y1304379I-299J266D01*
G02X173538Y1307823I1940J1734D01*
G03X173236Y1308486I-302J263D01*
G01X115192D01*
X112930Y1306224D01*
X109754D01*
G02Y1309202I-1755J1489D01*
G01X111696D01*
X113958Y1311464D01*
X123021D01*
G03X123303Y1312147I-1J400D01*
G01X120696Y1314754D01*
X120608Y1314750D01*
G02X122807Y1316949I-101J2300D01*
G01X122803Y1316861D01*
X125624Y1314040D01*
X155982D01*
X166482Y1324540D01*
X367766D01*
X369960Y1322346D01*
X370048Y1322350D01*
G02X367849Y1320151I101J-2300D01*
G01X367853Y1320239D01*
X366532Y1321560D01*
X167716D01*
X158303Y1312147D01*
G03X158585Y1311464I283J-283D01*
G37*
G36*
G01X146029Y1231912D02*
G03X146606I288J277D01*
G02X150432Y1228386I1879J-1800D01*
G03X150434Y1227853I299J-265D01*
G02X150439Y1224379I-1935J-1740D01*
G03Y1223847I299J-266D01*
G02X146614Y1220320I-1940J-1734D01*
G03X146034I-290J-276D01*
G02X142209Y1223847I-1885J1793D01*
G03Y1224379I-299J266D01*
G02Y1227847I1940J1734D01*
G03Y1228379I-299J266D01*
G02X146029Y1231912I1940J1735D01*
G37*
G36*
G01X104786Y1193914D02*
G03X104180Y1194136I-384J-110D01*
G02X105113Y1196686I-1280J1914D01*
G03X105719Y1196464I384J110D01*
G02X104786Y1193914I1280J-1914D01*
G37*
G36*
G01X261233Y1163490D02*
G03X261765I266J299D01*
G02X265449Y1163273I1734J-1940D01*
G03X266049I300J264D01*
G02X269733Y1163490I1950J-1723D01*
G03X270265I266J299D01*
G02Y1159610I1734J-1940D01*
G03X269733I-266J-299D01*
G02X266049Y1159827I-1734J1940D01*
G03X265449I-300J-264D01*
G02X261765Y1159610I-1950J1723D01*
G03X261233I-266J-299D01*
G02Y1163490I-1734J1940D01*
G37*
G36*
G01X785056Y1159942D02*
G03Y1159342I264J-300D01*
G02X781610I-1723J-1950D01*
G03Y1159942I-264J300D01*
G02X780880Y1162761I1723J1950D01*
G03X780481Y1163294I-377J134D01*
G02X778383Y1164169I-148J2598D01*
G03X777783I-300J-264D01*
G02X773883I-1950J1723D01*
G03X773283I-300J-264D01*
G02X773273Y1164158I-1930J1745D01*
G03Y1163626I299J-266D01*
G02X769393I-1940J-1734D01*
G03Y1164158I-299J266D01*
G02X773283Y1167615I1940J1734D01*
G03X773883I300J264D01*
G02X777783I1950J-1723D01*
G03X778383I300J264D01*
G02X782786Y1165023I1950J-1723D01*
G03X783185Y1164490I377J-134D01*
G02X785056Y1159942I148J-2598D01*
G37*
G36*
G01X262294Y1151085D02*
G03X261761Y1151077I-262J-302D01*
G02X261704Y1154957I-1762J1915D01*
G03X262237Y1154965I262J302D01*
G02X265949Y1154773I1762J-1915D01*
G03X266549I300J264D01*
G02X270233Y1154990I1950J-1723D01*
G03X270765I266J299D01*
G02Y1151110I1734J-1940D01*
G03X270233I-266J-299D01*
G02X266549Y1151327I-1734J1940D01*
G03X265949I-300J-264D01*
G02X262294Y1151085I-1950J1723D01*
G37*
G36*
G01X138701Y1126900D02*
X138789Y1126896D01*
X150083Y1138190D01*
X249745D01*
G02Y1135210I1755J-1490D01*
G01X151317D01*
X140896Y1124789D01*
X140900Y1124701D01*
G02X138701Y1126900I-2300J-101D01*
G37*
G36*
G01X800765Y1095626D02*
G03X800233I-266J-299D01*
G02Y1099506I-1734J1940D01*
G03X800765I266J299D01*
G02X804812Y1098758I1734J-1940D01*
G03X805478Y1098689I356J183D01*
G02X805559Y1098785I2029J-1630D01*
G03X805538Y1099340I-298J267D01*
G02X805661Y1103203I1803J1876D01*
G03X805615Y1103847I-259J305D01*
G02X805833Y1108376I1384J2203D01*
G03X805878Y1109064I-180J357D01*
G02X805901Y1113383I1463J2152D01*
G03Y1114049I-222J333D01*
G02X808781I1440J2167D01*
G03Y1113383I222J-333D01*
G02X808507Y1108890I-1440J-2167D01*
G03X808462Y1108202I180J-357D01*
G02X808679Y1104063I-1463J-2152D01*
G03X808725Y1103419I259J-305D01*
G02X809281Y1099481I-1384J-2204D01*
G03X809302Y1098926I298J-267D01*
G02X809356Y1098872I-1812J-1867D01*
G03X809642I143J140D01*
G02X809765Y1095110I1857J-1822D01*
G03X809233I-266J-299D01*
G02X805186Y1095858I-1734J1940D01*
G03X804520Y1095927I-356J-183D01*
G02X800765Y1095626I-2021J1639D01*
G37*
G36*
G01X367130Y1098040D02*
X743382D01*
X769703Y1124361D01*
X769699Y1124449D01*
G02X771898Y1122250I2300J101D01*
G01X771810Y1122254D01*
X744616Y1095060D01*
X347254D01*
G02X343257Y1097070I-1755J1490D01*
G03X342868Y1097560I-390J90D01*
G01X338616D01*
X329666Y1088610D01*
X240033D01*
X232133Y1096510D01*
X223117D01*
X213667Y1087060D01*
X167887D01*
X166903Y1086077D01*
X166931Y1085967D01*
G02X164219Y1087651I-2231J-567D01*
G01X164277Y1087664D01*
X166653Y1090040D01*
X212433D01*
X221883Y1099490D01*
X233367D01*
X241267Y1091590D01*
X328432D01*
X337382Y1100540D01*
X362744D01*
G02X366741Y1098530I1755J-1490D01*
G03X367130Y1098040I390J-90D01*
G37*
G36*
G01X853144Y1061451D02*
Y1061353D01*
X853138Y1061265D01*
G02X850800Y1059130I-2305J176D01*
G01X847200Y1059181D01*
G02X847266Y1063803I33J2311D01*
G01X850865Y1063752D01*
G02X853144Y1061451I-32J-2311D01*
G37*
G36*
G01X880544Y1051105D02*
Y1051007D01*
X880538Y1050919D01*
G02X875929Y1050912I-2305J177D01*
G01X875660Y1054302D01*
G02X880268Y1054668I2304J183D01*
G01X880292Y1054373D01*
X880537Y1051279D01*
G02X880544Y1051105I-2304J-180D01*
G37*
G36*
G01X882410Y976982D02*
X878697D01*
G03X878415Y976299I1J-400D01*
G01X880789Y973925D01*
X880814Y973911D01*
G02X877689Y970786I-1106J-2019D01*
G01X877675Y970811D01*
X874705Y973782D01*
X873644D01*
X820398Y1027027D01*
Y1070988D01*
X814813Y1076573D01*
X814764Y1076588D01*
G02X816046Y1081010I636J2212D01*
G01X816073Y1081002D01*
X816612D01*
X823647Y1073967D01*
G03X824206Y1073961I283J283D01*
G02X828010Y1071654I1594J-1661D01*
G01X828002Y1071627D01*
Y1030177D01*
X876794Y981384D01*
X882410D01*
X882437Y981393D01*
G02Y976973I646J-2210D01*
G01X882410Y976982D01*
G37*
G36*
G01X232002Y1063632D02*
Y1060081D01*
G03X232684Y1059798I400J0D01*
G01X239967Y1067081D01*
X239981Y1067106D01*
G02X243106Y1063981I2019J-1106D01*
G01X243081Y1063967D01*
X235202Y1056088D01*
Y1041988D01*
X159261Y966048D01*
X155422D01*
X155395Y966039D01*
G02Y970459I-646J2210D01*
G01X155422Y970450D01*
X157437D01*
X163251Y976265D01*
G03X162969Y976948I-283J283D01*
G01X155422D01*
X155395Y976939D01*
G02Y981359I-646J2210D01*
G01X155422Y981350D01*
X163811D01*
X168403Y985943D01*
G03X168121Y986626I-283J283D01*
G01X165173D01*
G02Y995028I0J4201D01*
G01X169473D01*
G02X173530Y991918I0J-4201D01*
G03X174199Y991739I386J104D01*
G01X227598Y1045138D01*
Y1072026D01*
G03X226916Y1072309I-400J0D01*
G01X224096Y1069489D01*
X224100Y1069401D01*
G02X221901Y1071600I-2300J-101D01*
G01X221989Y1071596D01*
X227883Y1077490D01*
X228152D01*
X228177Y1077514D01*
X240692D01*
X269667Y1048540D01*
X340352D01*
X340510Y1048382D01*
X340598Y1048386D01*
G02X338496Y1045419I101J-2300D01*
G01X338453Y1045560D01*
X268433D01*
X239458Y1074536D01*
X232448D01*
G03X232056Y1074056I0J-400D01*
G02X232010Y1072954I-2256J-458D01*
G01X232002Y1072927D01*
Y1068568D01*
G03X232564Y1068203I400J0D01*
G02Y1063997I936J-2103D01*
G03X232002Y1063632I-162J-365D01*
G37*
G36*
G01X216949Y950336D02*
G03X217549I300J264D01*
G02X221062Y946533I1950J-1723D01*
G03Y945893I240J-320D01*
G02X221358Y941993I-1563J-2080D01*
G03Y941433I286J-280D01*
G02X217549Y937890I-1859J-1820D01*
G03X216949I-300J-264D01*
G02X213276Y941563I-1950J1723D01*
G03Y942163I-264J300D01*
G02Y946063I1723J1950D01*
G03Y946663I-264J300D01*
G02X216949Y950336I1723J1950D01*
G37*
G36*
G01X111410Y928260D02*
Y928162D01*
X111404Y928074D01*
G02X106794Y928078I-2305J177D01*
G01X106540Y931485D01*
G02X111149Y931842I2305J172D01*
G01X111152Y931805D01*
X111404Y928423D01*
G02X111410Y928260I-2305J-166D01*
G37*
G36*
G01X216949Y928336D02*
G03X217549I300J264D01*
G02Y924890I1950J-1723D01*
G03X216949I-300J-264D01*
G02Y928336I-1950J1723D01*
G37*
G36*
G01X159222Y907100D02*
G03Y906500I264J-300D01*
G02X155776I-1723J-1950D01*
G03Y907100I-264J300D01*
G02X159222I1723J1950D01*
G37*
G36*
G01X154059Y893217D02*
G03Y893883I-222J333D01*
G02X156941Y898216I1440J2167D01*
G03X157468Y898292I221J333D01*
G02X161241Y898512I1991J-1676D01*
G03X161780Y898503I274J291D01*
G02X161717Y894654I1719J-1953D01*
G03X161178Y894663I-274J-291D01*
G02X158017Y894450I-1719J1953D01*
G03X157490Y894374I-221J-333D01*
G02X156939Y893883I-1989J1678D01*
G03Y893217I222J-333D01*
G02X154059I-1440J-2167D01*
G37*
G36*
G01X370010Y882355D02*
Y887883D01*
X366883Y891010D01*
X226203D01*
G03X225920Y890328I0J-400D01*
G01X227200Y889048D01*
Y883552D01*
X223997Y880348D01*
X204501D01*
X157501Y927348D01*
X151501D01*
X147798Y931052D01*
Y937048D01*
X150001Y939252D01*
X162681D01*
X162714Y939264D01*
G02X164349Y939240I786J-2164D01*
G01X164385Y939226D01*
X166724D01*
X169393Y936556D01*
X169534Y936687D01*
G02X169784Y936889I1568J-1685D01*
G03X169769Y937555I-229J328D01*
G02X172316Y937611I1231J1945D01*
G03X172331Y936945I229J-328D01*
G02X173097Y933855I-1231J-1945D01*
G03X173169Y933583I173J-100D01*
G02X174299Y931723I-1169J-1983D01*
G01X174303Y931646D01*
X209641Y896308D01*
G03X210194Y896296I283J283D01*
G02X214050Y894499I1556J-1696D01*
G01X214046Y894411D01*
X214467Y893990D01*
X368117D01*
X372990Y889117D01*
Y882355D01*
G02X370010I-1490J-1755D01*
G37*
G36*
G01X157821Y861193D02*
G03Y860907I140J-143D01*
G02X154059Y860784I-1822J-1857D01*
G03Y861316I-299J266D01*
G02X157733Y864990I1940J1734D01*
G03X158265I266J299D01*
G02X161733I1734J-1940D01*
G03X162265I266J299D01*
G02Y861110I1734J-1940D01*
G03X161733I-266J-299D01*
G02X158142Y861228I-1734J1940D01*
G03X157856I-143J-140D01*
G02X157821Y861193I-1857J1822D01*
G37*
G36*
G01X202644Y843771D02*
G03X202624Y844304I-308J255D01*
G02X206447Y847832I1872J1807D01*
G03X207047Y847833I300J265D01*
G02X210934Y844373I1953J-1720D01*
G03X210932Y843840I298J-268D01*
G02X210907Y840358I-1946J-1727D01*
G03X210909Y839817I296J-269D01*
G02X207114Y836257I-1910J-1767D01*
G03X206534I-290J-276D01*
G02X202733Y839811I-1885J1793D01*
G03Y840352I-294J271D01*
G02X202644Y843771I1916J1761D01*
G37*
G36*
G01X167718Y814028D02*
G03X167184Y813982I-242J-319D01*
G02X166887Y817387I-1685J1568D01*
G03X167421Y817433I242J319D01*
G02X167718Y814028I1685J-1568D01*
G37*
G36*
G01X293265Y756110D02*
G03X292733I-266J-299D01*
G02X289276Y760000I-1734J1940D01*
G03Y760600I-264J300D01*
G02Y764500I1723J1950D01*
G03Y765100I-264J300D01*
G02X292733Y768990I1723J1950D01*
G03X293265I266J299D01*
G02X296722Y765100I1734J-1940D01*
G03Y764500I264J-300D01*
G02Y760600I-1723J-1950D01*
G03Y760000I264J-300D01*
G02X293265Y756110I-1723J-1950D01*
G37*
G36*
G01X784919Y758432D02*
G03Y757832I264J-300D01*
G02X781473I-1723J-1950D01*
G03Y758432I-264J300D01*
G02X780743Y761251I1723J1950D01*
G03X780344Y761784I-377J134D01*
G02X778246Y762659I-148J2598D01*
G03X777646I-300J-264D01*
G02X773746I-1950J1723D01*
G03X773146I-300J-264D01*
G02X773136Y762648I-1930J1745D01*
G03Y762116I299J-266D01*
G02X769256I-1940J-1734D01*
G03Y762648I-299J266D01*
G02X773146Y766105I1940J1734D01*
G03X773746I300J264D01*
G02X777646I1950J-1723D01*
G03X778246I300J264D01*
G02X782649Y763513I1950J-1723D01*
G03X783048Y762980I377J-134D01*
G02X784919Y758432I148J-2598D01*
G37*
G36*
G01X305229Y755469D02*
G03X305274Y756102I-221J334D01*
G02X308256Y755772I1725J1948D01*
G03X308160Y755144I193J-351D01*
G02X305229Y755469I-1660J-1594D01*
G37*
G36*
G01X283663Y746739D02*
G03X283935I136J147D01*
G02Y743361I1564J-1689D01*
G03X283663I-136J-147D01*
G02Y746739I-1564J1689D01*
G37*
G36*
G01X329501Y742557D02*
G03X329521Y742277I152J-130D01*
G02X326247Y742043I-1522J-1727D01*
G03X326227Y742323I-152J130D01*
G02X329501Y742557I1522J1727D01*
G37*
G36*
G01X42027Y726803D02*
G03X41494Y726870I-303J-260D01*
G02X38060Y730734I-1494J2130D01*
G03Y731266I-299J266D01*
G02X38592Y735188I1940J1734D01*
G03Y735861I-216J336D01*
G02X38059Y739784I1407J2189D01*
G03Y740316I-299J266D01*
G02X41949Y743773I1940J1734D01*
G03X42549I300J264D01*
G02X45981Y739911I1950J-1723D01*
G03X45914Y739312I228J-329D01*
G02X45890Y735762I-1915J-1762D01*
G03X45956Y735156I290J-275D01*
G02X45982Y730861I-1456J-2156D01*
G03X45915Y730262I228J-329D01*
G02X42027Y726803I-1915J-1762D01*
G37*
G36*
G01X282675Y715559D02*
G03X282599Y715032I257J-306D01*
G02X278757Y715581I-2166J-1442D01*
G03X278833Y716108I-257J306D01*
G02X282675Y715559I2166J1442D01*
G37*
G36*
G01X282939Y703816D02*
G03Y703284I299J-266D01*
G02X279059I-1940J-1734D01*
G03Y703816I-299J266D01*
G02X282939I1940J1734D01*
G37*
G36*
G01X796054Y700903D02*
G03Y700303I264J-300D01*
G02X792608I-1723J-1950D01*
G03Y700903I-264J300D01*
G02Y704803I1723J1950D01*
G03Y705403I-264J300D01*
G02Y709303I1723J1950D01*
G03Y709903I-264J300D01*
G02X796054I1723J1950D01*
G03Y709303I264J-300D01*
G02Y705403I-1723J-1950D01*
G03Y704803I264J-300D01*
G02Y700903I-1723J-1950D01*
G37*
G36*
G01X808462Y699826D02*
G03X808485Y699186I251J-311D01*
G02X805368Y699077I-1486J-2136D01*
G03X805345Y699717I-251J311D01*
G02X805391Y704020I1486J2136D01*
G03Y704686I-222J333D01*
G02Y709020I1440J2167D01*
G03Y709686I-222J333D01*
G02X808271I1440J2167D01*
G03Y709020I222J-333D01*
G02Y704686I-1440J-2167D01*
G03Y704020I222J-333D01*
G02X808462Y699826I-1440J-2167D01*
G37*
G36*
G01X52602Y699220D02*
Y699217D01*
X52709Y695911D01*
Y695910D01*
G02X48108Y695763I-2299J-110D01*
G01Y695764D01*
X48001Y699088D01*
Y699089D01*
G02X52602Y699220I2299J111D01*
G37*
G36*
G01X851214Y653121D02*
X847814Y653059D01*
G02X847730Y657681I-42J2311D01*
G01X851129Y657743D01*
G02X853480Y655560I43J-2311D01*
G01X853482Y655522D01*
X853483Y655483D01*
G02Y655382I-2311J-51D01*
G01X853482Y655380D01*
Y655370D01*
G02X851214Y653121I-2310J62D01*
G37*
G36*
G01X880908Y649358D02*
Y645485D01*
X880901Y645397D01*
G02X876284Y645573I-2305J176D01*
G01Y649348D01*
G02X880908Y649358I2312J0D01*
G37*
G36*
G01X28870Y639558D02*
Y635996D01*
G02X24266I-2302J-46D01*
G01Y639558D01*
G02X28870I2302J46D01*
G37*
G36*
G01X127810Y638960D02*
Y635462D01*
X127804Y635374D01*
G02X123188Y635550I-2305J176D01*
G01Y638950D01*
G02X127810Y638960I2311J0D01*
G37*
G36*
G01X392349Y630701D02*
X392353Y630789D01*
X334134Y689008D01*
Y782308D01*
X320688Y795754D01*
X320600Y795750D01*
G02X322799Y797949I-101J2300D01*
G01X322795Y797861D01*
X337114Y783542D01*
Y690242D01*
X394460Y632896D01*
X394548Y632900D01*
G02X392349Y630701I101J-2300D01*
G37*
G36*
G01X41714Y627895D02*
G03X41963Y627785I184J79D01*
G02X40595Y624696I746J-2178D01*
G03X40346Y624806I-184J-79D01*
G02X41714Y627895I-746J2178D01*
G37*
G36*
G01X25197Y620249D02*
X25198Y620251D01*
Y623809D01*
X25197Y623811D01*
G02X29801I2302J46D01*
G01X29800Y623809D01*
Y620251D01*
X29801Y620249D01*
G02X25197I-2302J-46D01*
G37*
G36*
G01X556774Y614102D02*
G03X556215Y614074I-265J-299D01*
G02X552537Y617750I-1911J1766D01*
G03X552563Y618311I-271J294D01*
G02X552776Y622000I1936J1739D01*
G03Y622600I-264J300D01*
G02X556319Y626409I1723J1950D01*
G03X556879I280J286D01*
G02X560517Y622689I1820J-1859D01*
G03X560518Y622115I279J-287D01*
G02X560475Y618334I-1809J-1870D01*
G03X560447Y617775I271J-294D01*
G02X556774Y614102I-1948J-1725D01*
G37*
G36*
G01X30279Y604979D02*
G03X30231Y605250I-167J110D01*
G02X33519Y605833I1367J1852D01*
G03X33567Y605562I167J-110D01*
G02X30279Y604979I-1367J-1852D01*
G37*
G36*
G01X27070Y594660D02*
G03X27062Y594932I-150J132D01*
G02X30438Y595039I1638J1617D01*
G03X30446Y594767I150J-132D01*
G02X27070Y594660I-1638J-1617D01*
G37*
G36*
G01X819602Y672612D02*
Y666935D01*
G03X820090Y666545I400J0D01*
G02X822810Y663654I510J-2245D01*
G01X822802Y663627D01*
Y628777D01*
X878827Y572752D01*
X879077D01*
X879104Y572760D01*
G02X880534Y568385I646J-2210D01*
G03X880387Y567727I136J-376D01*
G01X881031Y567083D01*
X881056Y567069D01*
G02X877931Y563944I-1106J-2019D01*
G01X877917Y563969D01*
X876738Y565148D01*
X875677D01*
X815198Y625627D01*
Y670788D01*
X812119Y673867D01*
X812094Y673881D01*
G02X815219Y677006I1106J2019D01*
G01X815233Y676981D01*
X819602Y672612D01*
G37*
G36*
G01X142633Y564023D02*
G03X142579Y563416I231J-326D01*
G02X139607Y563677I-1639J-1616D01*
G03X139661Y564284I-231J326D01*
G02X142633Y564023I1639J1616D01*
G37*
G36*
G01X32177Y555933D02*
G03X31912Y555870I-99J-174D01*
G02X31129Y559155I-1913J1280D01*
G03X31394Y559218I99J174D01*
G02X31903Y559762I1913J-1280D01*
G03X31961Y560341I-244J317D01*
G02X35103Y560026I1738J1509D01*
G03X35045Y559447I244J-317D01*
G02X32177Y555933I-1739J-1508D01*
G37*
G36*
G01X107564Y544889D02*
G03X107836I136J147D01*
G02Y541511I1564J-1689D01*
G03X107564I-136J-147D01*
G02Y544889I-1564J1689D01*
G37*
G36*
G01X88510Y536035D02*
Y532162D01*
X88504Y532074D01*
G02X83888Y532250I-2305J176D01*
G01Y536025D01*
G02X88510Y536035I2311J0D01*
G37*
G36*
G01X151549Y500827D02*
G03X150949I-300J-264D01*
G02Y504273I-1950J1723D01*
G03X151549I300J264D01*
G02Y500827I1950J-1723D01*
G37*
G36*
G01X28710Y505751D02*
Y501878D01*
X28704Y501790D01*
G02X24088Y501966I-2305J176D01*
G01Y505741D01*
G02X28710Y505751I2311J0D01*
G37*
G36*
G01X138119Y500909D02*
G03X138679I280J286D01*
G02Y497191I1820J-1859D01*
G03X138119I-280J-286D01*
G02Y500909I-1820J1859D01*
G37*
G36*
G01X187593Y486766D02*
G03X187919Y487211I-71J394D01*
G02X188914Y489614I2580J339D01*
G03X189008Y490147I-243J318D01*
G02X188781Y490588I2189J1406D01*
G03X188524Y490701I-186J-74D01*
G02X189727Y493940I-825J2149D01*
G03X189995Y493857I176J94D01*
G02X193546Y492673I1204J-2307D01*
G03X194052Y492474I360J173D01*
G02X193699Y487796I947J-2424D01*
G03X193100Y487463I-199J-347D01*
G02X190674Y484954I-2601J87D01*
G03X190302Y484547I28J-399D01*
G02X187593Y486766I-2302J-47D01*
G37*
G36*
G01X62092Y471042D02*
X62086Y474442D01*
G02X66701Y474631I2311J4D01*
G01X66708Y474539D01*
Y474442D01*
X66715Y470960D01*
X66708Y470870D01*
G02X62092Y471042I-2305J177D01*
G37*
G36*
G01X91681Y447160D02*
G03X91640Y447766I-280J285D01*
G02X95149Y451573I1560J2083D01*
G03X95749I300J264D01*
G02X99636Y448113I1950J-1723D01*
G03X99676Y447540I298J-267D01*
G02X96145Y443725I-1676J-1990D01*
G03X95545Y443691I-285J-281D01*
G02X91681Y447160I-2045J1608D01*
G37*
G36*
G01X24182Y439423D02*
X24289Y442822D01*
G02X28910Y442759I2310J-73D01*
G01Y442749D01*
X28911D01*
G02Y442739I-2312J-5D01*
G01X28910D01*
Y442708D01*
X28802Y439235D01*
X28797Y439174D01*
G02X24182Y439423I-2305J176D01*
G37*
G36*
G01X177874Y440452D02*
G03X177920Y440985I-273J292D01*
G02X178276Y444500I2079J1565D01*
G03Y445100I-264J300D01*
G02X181733Y448990I1723J1950D01*
G03X182265I266J299D01*
G02X185722Y445100I1734J-1940D01*
G03Y444500I264J-300D01*
G02X185939Y440816I-1723J-1950D01*
G03Y440284I299J-266D01*
G02X182114Y436757I-1940J-1734D01*
G03X181534I-290J-276D01*
G02X177874Y440452I-1885J1793D01*
G37*
G36*
G01X142774Y425633D02*
G03Y424967I221J-333D01*
G02X140224I-1275J-1917D01*
G03Y425633I-221J333D01*
G02X142774I1275J1917D01*
G37*
G36*
G01X398744Y404840D02*
X346275D01*
G02Y407818I-1755J1489D01*
G01X398744D01*
G02Y404840I1755J-1489D01*
G37*
G36*
G01X28610Y403386D02*
Y399513D01*
X28604Y399425D01*
G02X23988Y399601I-2305J176D01*
G01Y403376D01*
G02X28610Y403386I2311J0D01*
G37*
G36*
G01X292264Y350174D02*
G03X291732I-266J-299D01*
G02X288275Y354064I-1734J1940D01*
G03Y354664I-264J300D01*
G02Y358564I1723J1950D01*
G03Y359164I-264J300D01*
G02X291732Y363054I1723J1950D01*
G03X292264I266J299D01*
G02X295721Y359164I1734J-1940D01*
G03Y358564I264J-300D01*
G02Y354664I-1723J-1950D01*
G03Y354064I264J-300D01*
G02X292264Y350174I-1723J-1950D01*
G37*
G36*
G01X283436Y336960D02*
G03X283156Y336952I-136J-147D01*
G02X283062Y340240I-1657J1598D01*
G03X283342Y340248I136J147D01*
G02X283436Y336960I1657J-1598D01*
G37*
G36*
G01X328188Y335890D02*
G03Y335618I147J-136D01*
G02X324810I-1689J-1564D01*
G03Y335890I-147J136D01*
G02X328188I1689J1564D01*
G37*
G36*
G01X559939Y324816D02*
G03Y324284I299J-266D01*
G02X556059I-1940J-1734D01*
G03Y324816I-299J266D01*
G02X556229Y328457I1940J1734D01*
G03X556220Y329051I-272J293D01*
G02X556083Y332840I1713J1959D01*
G03X556105Y333378I-284J281D01*
G02X559949Y333220I1994J1672D01*
G03X559927Y332682I284J-281D01*
G02X559703Y329103I-1994J-1672D01*
G03X559712Y328509I272J-293D01*
G02X559939Y324816I-1713J-1959D01*
G37*
G36*
G01X754057Y312384D02*
G03X753530Y312308I-221J-333D01*
G02X749607Y315727I-1991J1676D01*
G03X749602Y316269I-297J268D01*
G02X752633Y320392I1897J1781D01*
G03X753146Y320538I175J360D01*
G02X757083Y317211I2200J-1390D01*
G03X757103Y316599I267J-298D01*
G02X754057Y312384I-1603J-2050D01*
G37*
G36*
G01X281721Y297664D02*
G03Y297064I264J-300D01*
G02X278275I-1723J-1950D01*
G03Y297664I-264J300D01*
G02Y301564I1723J1950D01*
G03Y302164I-264J300D01*
G02Y306064I1723J1950D01*
G03Y306664I-264J300D01*
G02X281721I1723J1950D01*
G03Y306064I264J-300D01*
G02Y302164I-1723J-1950D01*
G03Y301564I264J-300D01*
G02Y297664I-1723J-1950D01*
G37*
G36*
G01X798596Y296621D02*
G03Y296021I264J-300D01*
G02X795150I-1723J-1950D01*
G03Y296621I-264J300D01*
G02Y300521I1723J1950D01*
G03Y301121I-264J300D01*
G02Y305021I1723J1950D01*
G03Y305621I-264J300D01*
G02X798596I1723J1950D01*
G03Y305021I264J-300D01*
G02Y301121I-1723J-1950D01*
G03Y300521I264J-300D01*
G02Y296621I-1723J-1950D01*
G37*
G36*
G01X853590Y249984D02*
Y249886D01*
X853583Y249798D01*
G02X851233Y247663I-2305J176D01*
G01X847834Y247729D01*
G02X847923Y252351I44J2311D01*
G01X851323Y252285D01*
G02X853590Y249984I-45J-2311D01*
G37*
G36*
G01X125110Y249184D02*
Y249062D01*
X125104Y248974D01*
G02X120530Y248708I-2305J175D01*
G01X120496Y248887D01*
X120493Y248886D01*
X120090Y252426D01*
X120098Y252433D01*
X120092Y252524D01*
G02X124666Y253130I2305J164D01*
G01X124700Y252951D01*
X124703Y252952D01*
X124722Y252787D01*
X125106Y249411D01*
X125103Y249410D01*
X125109Y249224D01*
G02X125110Y249184I-2310J-78D01*
G37*
G36*
G01X880390Y243888D02*
Y240015D01*
X880383Y239927D01*
G02X875766Y240103I-2305J176D01*
G01Y243878D01*
G02X880390Y243888I2312J0D01*
G37*
G36*
G01X152310Y243514D02*
Y239641D01*
X152304Y239553D01*
G02X147688Y239729I-2305J176D01*
G01Y243504D01*
G02X152310Y243514I2311J0D01*
G37*
G36*
G01X294633Y291337D02*
X294488Y291296D01*
Y264433D01*
X220795Y190739D01*
X220799Y190651D01*
G02X218600Y192850I-2300J-101D01*
G01X218688Y192846D01*
X291510Y265667D01*
Y293167D01*
X291703Y293361D01*
X291699Y293449D01*
G02X294633Y291337I2300J101D01*
G37*
G36*
G01X226276Y184500D02*
G03Y185100I-264J300D01*
G02X226365Y189075I1723J1950D01*
G03X226299Y189741I-251J311D01*
G02X229449Y193773I1200J2309D01*
G03X230049I300J264D01*
G02X233439Y189883I1950J-1723D01*
G03Y189217I222J-333D01*
G02X233722Y185100I-1440J-2167D01*
G03Y184500I264J-300D01*
G02Y180600I-1723J-1950D01*
G03Y180000I264J-300D01*
G02X230265Y176110I-1723J-1950D01*
G03X229733I-266J-299D01*
G02X226276Y180000I-1734J1940D01*
G03Y180600I-264J300D01*
G02Y184500I1723J1950D01*
G37*
G36*
G01X821102Y273012D02*
Y264335D01*
G03X821590Y263945I400J0D01*
G02X824310Y261054I510J-2245D01*
G01X824302Y261027D01*
Y249412D01*
X860902Y212812D01*
Y173636D01*
X868581Y165957D01*
X868606Y165943D01*
G02X869080Y162249I-1106J-2019D01*
G03X869091Y161657I274J-291D01*
G02X866930Y157714I-1515J-1733D01*
G01X866903Y157722D01*
X866062D01*
X853298Y170486D01*
Y209662D01*
X816698Y246262D01*
Y271188D01*
X815619Y272267D01*
X815594Y272281D01*
G02X818719Y275406I1106J2019D01*
G01X818733Y275381D01*
X821102Y273012D01*
G37*
G36*
G01X756265Y152610D02*
G03X755733I-266J-299D01*
G02X752276Y156500I-1734J1940D01*
G03Y157100I-264J300D01*
G02X755733Y160990I1723J1950D01*
G03X756265I266J299D01*
G02X759722Y157100I1734J-1940D01*
G03Y156500I264J-300D01*
G02X756265Y152610I-1723J-1950D01*
G37*
G36*
G01X34798Y135039D02*
G03X34171Y135025I-308J-256D01*
G02X34102Y138261I-2071J1575D01*
G03X34729Y138275I308J256D01*
G02X34798Y135039I2071J-1575D01*
G37*
G36*
G01X34224Y132204D02*
G03X34876I326J231D01*
G02Y129196I2124J-1504D01*
G03X34224I-326J-231D01*
G02Y132204I-2124J1504D01*
G37*
G36*
G01X84295Y126931D02*
X84595Y130747D01*
G02X89210Y130577I2304J-180D01*
G01Y130567D01*
X89211D01*
G02Y130564I-2312J-2D01*
G01X89210D01*
Y130478D01*
X89204Y130391D01*
G02X89203Y130386I-2267J451D01*
G01X88904Y126579D01*
X88903Y126569D01*
G02X84295Y126931I-2304J181D01*
G37*
G36*
G01X113749Y126854D02*
X113764Y126891D01*
Y129132D01*
X113749Y129169D01*
G02X118003I2127J881D01*
G01X117988Y129132D01*
Y126891D01*
X118003Y126854D01*
G02X113749I-2127J-881D01*
G37*
G36*
G01X350049Y111327D02*
G03X349449I-300J-264D01*
G02Y114773I-1950J1723D01*
G03X350049I300J264D01*
G02X353949I1950J-1723D01*
G03X354549I300J264D01*
G02X358449I1950J-1723D01*
G03X359049I300J264D01*
G02Y111327I1950J-1723D01*
G03X358449I-300J-264D01*
G02X354549I-1950J1723D01*
G03X353949I-300J-264D01*
G02X350049I-1950J1723D01*
G37*
G36*
G01X900889Y108905D02*
G03X900609I-140J-143D01*
G02Y112195I-1610J1645D01*
G03X900889I140J143D01*
G02Y108905I1610J-1645D01*
G37*
G36*
G01X348832Y99110D02*
G03X348166I-333J-222D01*
G02Y101990I-2167J1440D01*
G03X348832I333J222D01*
G02X353166I2167J-1440D01*
G03X353832I333J222D01*
G02X358166I2167J-1440D01*
G03X358832I333J222D01*
G02Y99110I2167J-1440D01*
G03X358166I-333J-222D01*
G02X353832I-2167J1440D01*
G03X353166I-333J-222D01*
G02X348832I-2167J1440D01*
G37*
G36*
G01X889017Y97950D02*
G03X888490Y97874I-221J-333D01*
G02X885059Y101717I-1990J1676D01*
G03Y102383I-222J333D01*
G02X888233Y106490I1440J2167D01*
G03X888765I266J299D01*
G02X892236Y102613I1734J-1940D01*
G03X892231Y102022I267J-298D01*
G02X889017Y97950I-1771J-1907D01*
G37*
G36*
G01X900343Y90059D02*
G03X899759Y89829I-201J-346D01*
G02X898711Y92485I-2204J665D01*
G03X899295Y92715I201J346D01*
G02X900343Y90059I2204J-665D01*
G37*
G36*
G01X841600Y85137D02*
G03X842199Y84804I400J14D01*
G02X840898Y82463I1300J-2254D01*
G03X840299Y82796I-400J-14D01*
G02X841600Y85137I-1300J2254D01*
G37*
G36*
G01X76188Y82486D02*
G03Y82214I147J-136D01*
G02X72810I-1689J-1564D01*
G03Y82486I-147J136D01*
G02X76188I1689J1564D01*
G37*
G36*
G01X177295Y77502D02*
G03X176703I-296J-269D01*
G02Y80598I-1704J1548D01*
G03X177295I296J269D01*
G02Y77502I1704J-1548D01*
G37*
G36*
G01X168222Y81600D02*
G03Y81000I264J-300D01*
G02X164776I-1723J-1950D01*
G03Y81600I-264J300D01*
G02X165017Y85689I1723J1950D01*
G03X165084Y86288I-228J329D01*
G02X165276Y90000I1915J1762D01*
G03Y90600I-264J300D01*
G02Y94500I1723J1950D01*
G03Y95100I-264J300D01*
G02X168722I1723J1950D01*
G03Y94500I264J-300D01*
G02Y90600I-1723J-1950D01*
G03Y90000I264J-300D01*
G02X168481Y85911I-1723J-1950D01*
G03X168414Y85312I228J-329D01*
G02X168222Y81600I-1915J-1762D01*
G37*
G36*
G01X159939Y81883D02*
G03Y81217I222J-333D01*
G02X157059I-1440J-2167D01*
G03Y81883I-222J333D01*
G02X156776Y86000I1440J2167D01*
G03Y86600I-264J300D01*
G02X157059Y90717I1723J1950D01*
G03Y91383I-222J333D01*
G02X159939I1440J2167D01*
G03Y90717I222J-333D01*
G02X160222Y86600I-1440J-2167D01*
G03Y86000I264J-300D01*
G02X159939Y81883I-1723J-1950D01*
G37*
G36*
G01X306454Y74913D02*
G03X307053Y74713I377J133D01*
G02X306044Y71687I1446J-2163D01*
G03X305445Y71887I-377J-133D01*
G02X306454Y74913I-1446J2163D01*
G37*
G36*
G01X77191Y68961D02*
G03X76643Y68939I-262J-302D01*
G02X73354Y72160I-1644J1611D01*
G03Y72440I-143J140D01*
G02X76508Y75789I1645J1611D01*
G03X77056Y75811I262J302D01*
G02X80345Y72590I1644J-1611D01*
G03Y72310I143J-140D01*
G02X77191Y68961I-1645J-1611D01*
G37*
G36*
G01X291779Y70652D02*
G03X291913Y69986I274J-291D01*
G02X289219Y69448I-914J-2436D01*
G03X289085Y70114I-274J291D01*
G02X287637Y73642I914J2436D01*
G03X287437Y74175I-363J168D01*
G02X287097Y78742I1062J2375D01*
G03X287231Y79275I-215J337D01*
G02X290901Y78358I2268J1275D01*
G03X290767Y77825I215J-337D01*
G02X290861Y75458I-2268J-1275D01*
G03X291061Y74925I363J-168D01*
G02X291779Y70652I-1062J-2375D01*
G37*
G36*
G01X379549Y63827D02*
G03X378949I-300J-264D01*
G02X375276Y67500I-1950J1723D01*
G03Y68100I-264J300D01*
G02X378949Y71773I1723J1950D01*
G03X379549I300J264D01*
G02X383222Y68100I1950J-1723D01*
G03Y67500I264J-300D01*
G02X379549Y63827I-1723J-1950D01*
G37*
G36*
G01X343018Y65380D02*
G03Y64780I264J-300D01*
G02X339980I-1519J-1730D01*
G03Y65380I-264J300D01*
G02X343018I1519J1730D01*
G37*
G36*
G01X323502Y95561D02*
Y93312D01*
X325135Y91678D01*
X325197Y91667D01*
G02X324154Y87190I-397J-2267D01*
G01X324127Y87198D01*
X323388D01*
X319098Y91488D01*
Y98614D01*
X318369Y99343D01*
G03X317748Y99274I-283J-283D01*
G02X313781Y99394I-1948J1226D01*
G01X313767Y99419D01*
X260599Y152588D01*
X146449D01*
X100993Y198044D01*
G03X100349Y197933I-283J-283D01*
G02X96882Y201400I-2350J1117D01*
G03X96993Y202044I-172J361D01*
G01X96688Y202348D01*
X96023D01*
X95996Y202340D01*
G02X93380Y205742I-646J2210D01*
G03X93038Y206348I-342J206D01*
G01X90473D01*
X90446Y206340D01*
G02Y210760I-646J2210D01*
G01X90473Y210752D01*
X98098D01*
G03X98381Y211434I0J400D01*
G01X95255Y214560D01*
X67754D01*
G02Y217540I-1755J1490D01*
G01X96489D01*
X146516Y167511D01*
G03X147198Y167794I282J283D01*
G01Y169612D01*
X151588Y174002D01*
X167691D01*
X168608Y174919D01*
G03X168326Y175602I-283J283D01*
G01X165173D01*
G02Y184004I0J4201D01*
G01X169473D01*
G02X171840Y176332I0J-4201D01*
G03X172065Y175602I226J-330D01*
G01X174727D01*
X236648Y237523D01*
Y276488D01*
X237398Y277238D01*
Y277927D01*
X237390Y277954D01*
G02X241810I2210J646D01*
G01X241802Y277927D01*
Y277597D01*
G03X242143Y277456I200J1D01*
G01X248122Y283435D01*
X248133Y283497D01*
G02X252512Y284015I2267J-397D01*
G03X253162Y283891I367J159D01*
G01X264960Y295689D01*
X264973Y295743D01*
G02X266058Y297281I2525J-629D01*
G03Y297947I-222J333D01*
G02Y302281I1440J2167D01*
G03Y302947I-222J333D01*
G02Y307281I1440J2167D01*
G03Y307947I-222J333D01*
G02X268938I1440J2167D01*
G03Y307281I222J-333D01*
G02Y302947I-1440J-2167D01*
G03Y302281I222J-333D01*
G02Y297947I-1440J-2167D01*
G03Y297281I222J-333D01*
G02X268127Y292589I-1440J-2167D01*
G01X268073Y292576D01*
X252502Y277004D01*
Y275773D01*
X252510Y275746D01*
G02X248090I-2210J-646D01*
G01X248098Y275773D01*
Y276219D01*
G03X247416Y276502I-400J0D01*
G01X244252Y273338D01*
Y234373D01*
X177877Y167998D01*
X175878D01*
G03X175526Y167409I0J-400D01*
G02X171198Y166276I-2026J-1093D01*
G01X171197Y166357D01*
X170998Y166556D01*
X170741Y166298D01*
X154873D01*
X154846Y166290D01*
G02X152011Y167787I-646J2210D01*
G01X151996Y167832D01*
X151821Y168008D01*
X151602Y167788D01*
Y167073D01*
X151610Y167046D01*
G02X150430Y164341I-2210J-646D01*
G03X150326Y163701I179J-358D01*
G01X151437Y162590D01*
X224783D01*
X227383Y165190D01*
X230917D01*
X233817Y162290D01*
X264817D01*
X320800Y106307D01*
G03X321426Y106384I283J283D01*
G02X324584Y103226I1974J-1184D01*
G03X324507Y102600I206J-343D01*
G01X325890Y101217D01*
Y98352D01*
X352048Y72193D01*
G03X352726Y72413I283J283D01*
G02X355362Y69777I2273J-363D01*
G03X355142Y69099I63J-395D01*
G01X360488Y63753D01*
Y63307D01*
X360553Y63248D01*
G02X357044Y62766I-1554J-1698D01*
G01X357128Y62901D01*
X324184Y95844D01*
G03X323502Y95561I-282J-283D01*
G37*
G36*
G01X944439Y64383D02*
G03Y63717I222J-333D01*
G02X941559I-1440J-2167D01*
G03Y64383I-222J333D01*
G02X944439I1440J2167D01*
G37*
G36*
G01X906633Y59525D02*
G03X906699Y58859I251J-311D01*
G02X903865Y58575I-1200J-2309D01*
G03X903799Y59241I-251J311D01*
G02X906633Y59525I1200J2309D01*
G37*
G36*
G01X383644Y55440D02*
G03Y55160I143J-140D01*
G02X380354I-1645J-1610D01*
G03Y55440I-143J140D01*
G02X383644I1645J1610D01*
G37*
G36*
G01X930481Y53911D02*
G03X930414Y53312I228J-329D01*
G02X927017Y53689I-1915J-1762D01*
G03X927084Y54288I-228J329D01*
G02Y57812I1915J1762D01*
G03X927017Y58411I-295J270D01*
G02X927299Y62859I1482J2139D01*
G03X927365Y63525I-185J355D01*
G02X930199Y63241I1634J2025D01*
G03X930133Y62575I185J-355D01*
G02X930414Y58788I-1634J-2025D01*
G03X930481Y58189I295J-270D01*
G02Y53911I-1482J-2139D01*
G37*
G36*
G01X192327Y37906D02*
G03X191727Y37806I-257J-306D01*
G02X191171Y41144I-2228J1344D01*
G03X191771Y41244I257J306D01*
G02X192361Y41922I2228J-1343D01*
G03X192428Y42475I-251J311D01*
G02X196865Y42968I2071J1575D01*
G03X197332Y42415I364J-166D01*
G02X196265Y37960I667J-2515D01*
G03X195733I-266J-299D01*
G02X192327Y37906I-1734J1940D01*
G37*
G36*
G01X943474Y31916D02*
G03X942808Y31850I-311J-251D01*
G02X942524Y34684I-2309J1200D01*
G03X943190Y34750I311J251D01*
G02X943474Y31916I2309J-1200D01*
G37*
G36*
G01X374549Y13827D02*
G03X373949I-300J-264D01*
G02X369458Y16110I-1950J1723D01*
G03X369192Y16576I-391J86D01*
G02X368276Y21000I807J2474D01*
G03Y21600I-264J300D01*
G02X371722I1723J1950D01*
G03Y21000I264J-300D01*
G02X372540Y18490I-1723J-1950D01*
G03X372806Y18024I391J-86D01*
G02X373949Y17273I-807J-2474D01*
G03X374549I300J264D01*
G02X378449I1950J-1723D01*
G03X379049I300J264D01*
G02X380136Y18005I1950J-1723D01*
G03X380336Y18604I-133J377D01*
G02X383362Y17595I2163J1446D01*
G03X383162Y16996I133J-377D01*
G02X379049Y13827I-2163J-1446D01*
G03X378449I-300J-264D01*
G02X374549I-1950J1723D01*
G37*
G36*
G01X294383Y38133D02*
X306501Y50252D01*
X312997D01*
X317200Y46048D01*
Y41052D01*
X284997Y8848D01*
X149001D01*
X140438Y17412D01*
G03X139756Y17152I-283J-283D01*
G02X121595Y22985I-9836J564D01*
G03X121257Y23598I-338J213D01*
G01X95251D01*
X78298Y40552D01*
Y46048D01*
X80001Y47752D01*
X82133D01*
G03X82416Y48434I0J400D01*
G01X81798Y49052D01*
Y55548D01*
X84001Y57752D01*
X101497D01*
X113497Y45752D01*
X147497D01*
X160997Y32252D01*
X272501D01*
X286001Y45752D01*
X289997D01*
X293700Y42048D01*
Y38416D01*
G03X294383Y38133I400J0D01*
G37*
G36*
G01X771383Y1929007D02*
G02Y1931093I-2384J1043D01*
G03X772115I366J161D01*
G02Y1929007I2384J-1043D01*
G03X771383I-366J-161D01*
G37*
G36*
G01X754634Y1764060D02*
G02X751271Y1768029I-1734J1940D01*
G03X751359Y1768555I-250J312D01*
G02X754997Y1772114I2199J1391D01*
G03X755525Y1772190I222J333D01*
G02X755657Y1772335I1989J-1678D01*
G03X755454Y1773006I-286J280D01*
G02X754265Y1773610I545J2544D01*
G03X753733I-266J-299D01*
G02X750370Y1777579I-1734J1940D01*
G03X750458Y1778105I-250J312D01*
G02X754096Y1781664I2199J1391D01*
G03X754624Y1781740I222J333D01*
G02X758027Y1777880I1993J-1673D01*
G03X757944Y1777278I216J-337D01*
G02X757860Y1773732I-1945J-1728D01*
G03X758063Y1773061I286J-280D01*
G02X758928Y1768330I-545J-2544D01*
G03X758845Y1767728I216J-337D01*
G02X755166Y1764060I-1946J-1728D01*
G03X754634I-266J-299D01*
G37*
G36*
G01X197328Y1621130D02*
G02X193985Y1621057I-1628J-2030D01*
G03X193972Y1621670I-263J301D01*
G02X196692Y1626062I1628J2030D01*
G03X197251Y1626510I168J363D01*
G02X198644Y1624863I2249J490D01*
G03X198110Y1624386I-148J-371D01*
G02X197315Y1621743I-2510J-686D01*
G03X197328Y1621130I263J-301D01*
G37*
G36*
G01X564542Y1488934D02*
G02X562456I-1043J-2384D01*
G03Y1489666I-161J366D01*
G02Y1494434I1043J2384D01*
G03Y1495166I-161J366D01*
G02X564542I1043J2384D01*
G03Y1494434I161J-366D01*
G02Y1489666I-1043J-2384D01*
G03Y1488934I161J-366D01*
G37*
G36*
G01X967723Y1476950D02*
G02X964277I-1723J-1950D01*
G03Y1477550I-264J300D01*
G02Y1481450I1723J1950D01*
G03Y1482050I-264J300D01*
G02X964656Y1486228I1723J1950D01*
G03X964616Y1486934I-206J342D01*
G02X967044Y1487072I1083J2366D01*
G03X967084Y1486366I206J-342D01*
G02X967723Y1482050I-1084J-2366D01*
G03Y1481450I264J-300D01*
G02Y1477550I-1723J-1950D01*
G03Y1476950I264J-300D01*
G37*
G36*
G01X975223Y1475950D02*
G02X971777I-1723J-1950D01*
G03Y1476550I-264J300D01*
G02Y1480450I1723J1950D01*
G03Y1481050I-264J300D01*
G02X972156Y1485228I1723J1950D01*
G03X972116Y1485934I-206J342D01*
G02X974544Y1486072I1083J2366D01*
G03X974584Y1485366I206J-342D01*
G02X975223Y1481050I-1084J-2366D01*
G03Y1480450I264J-300D01*
G02Y1476550I-1723J-1950D01*
G03Y1475950I264J-300D01*
G37*
G36*
G01X960523Y1474450D02*
G02X957077I-1723J-1950D01*
G03Y1475050I-264J300D01*
G02Y1478950I1723J1950D01*
G03Y1479550I-264J300D01*
G02X957456Y1483728I1723J1950D01*
G03X957416Y1484434I-206J342D01*
G02X959844Y1484572I1083J2366D01*
G03X959884Y1483866I206J-342D01*
G02X960523Y1479550I-1084J-2366D01*
G03Y1478950I264J-300D01*
G02Y1475050I-1723J-1950D01*
G03Y1474450I264J-300D01*
G37*
G36*
G01X235902Y1480927D02*
Y1468581D01*
G03X236584Y1468298I400J0D01*
G01X238967Y1470681D01*
X238981Y1470706D01*
G02X242106Y1467581I2019J-1106D01*
G01X242081Y1467567D01*
X186802Y1412288D01*
Y1368188D01*
X183033Y1364419D01*
X183019Y1364394D01*
G02X179476Y1367225I-2019J1106D01*
G03X179402Y1367877I-265J300D01*
G02X179198Y1371799I1098J2023D01*
G01Y1415438D01*
X231498Y1467738D01*
Y1469844D01*
G03X230792Y1470100I-400J-1D01*
G02Y1473052I-1767J1476D01*
G03X231498Y1473308I306J257D01*
G01Y1480927D01*
X231490Y1480954D01*
G02X235910I2210J646D01*
G01X235902Y1480927D01*
G37*
G36*
G01X747865Y1122060D02*
X374754D01*
G02Y1125040I-1755J1490D01*
G01X760382D01*
X771382Y1136040D01*
X787330D01*
G03X787651Y1136678I0J400D01*
G02X791775Y1138392I1848J1373D01*
G03X791988Y1138222I198J30D01*
G02X792053Y1133626I165J-2296D01*
G01X791965Y1133630D01*
X791395Y1133060D01*
X781668D01*
G03X781347Y1132422I0J-400D01*
G02X777651I-1848J-1372D01*
G03X777330Y1133060I-321J238D01*
G01X772616D01*
X772105Y1132550D01*
X772309Y1132346D01*
X772397Y1132350D01*
G02X770217Y1129751I102J-2300D01*
G03X769537Y1129982I-397J-52D01*
G01X761616Y1122060D01*
X752133D01*
G03X751849Y1121379I1J-400D01*
G02X752475Y1120350I-1849J-1830D01*
G03X753208Y1120283I381J123D01*
G02X753023Y1118250I2291J-1233D01*
G03X752290Y1118317I-381J-123D01*
G02X751401Y1117358I-2291J1233D01*
G03X751267Y1116825I215J-337D01*
G02X750696Y1113577I-2268J-1275D01*
G03X750629Y1113044I260J-303D01*
G02X746802Y1113523I-2130J-1494D01*
G03X746869Y1114056I-260J303D01*
G02X747597Y1117742I2130J1494D01*
G03X747731Y1118275I-215J337D01*
G02X748149Y1121379I2268J1275D01*
G03X747865Y1122060I-285J281D01*
G37*
G36*
G01X157542Y872934D02*
G02X155456I-1043J-2384D01*
G03Y873666I-161J366D01*
G02X157542I1043J2384D01*
G03Y872934I161J-366D01*
G37*
G36*
G01X28915Y575704D02*
G02X26739Y575842I-1216J-1954D01*
G03X26784Y576546I-166J364D01*
G02X28960Y576408I1216J1954D01*
G03X28915Y575704I166J-364D01*
G37*
G36*
G01X154536Y834891D02*
Y835757D01*
X154373Y835788D01*
G02X157099Y837949I426J2262D01*
G01X157095Y837861D01*
X157516Y837440D01*
Y761167D01*
X160291Y758392D01*
G03X160973Y758663I282J283D01*
G02X165173Y762744I4200J-121D01*
G01X169473D01*
G02Y754342I0J-4201D01*
G01X165173D01*
G02X164825Y754356I-5J4201D01*
G01X164733Y754364D01*
X164526Y754157D01*
X167190Y751493D01*
Y595134D01*
X155990Y583934D01*
Y576482D01*
G03X156480Y576093I400J1D01*
G02X157646Y576061I522J-2242D01*
G01X157673Y576052D01*
X158178D01*
G03X158570Y576534I0J400D01*
G02X161470Y579210I2254J466D01*
G01X161497Y579202D01*
X176923D01*
X206073Y608352D01*
X206789D01*
X207198Y608760D01*
Y609476D01*
X236298Y638577D01*
Y680127D01*
X236290Y680154D01*
G02X240219Y682331I2210J646D01*
G03X240801Y682314I299J266D01*
G01X247598Y689112D01*
Y689227D01*
X247590Y689254D01*
G02X252010I2210J646D01*
G01X252002Y689227D01*
Y689132D01*
G03X252684Y688849I400J0D01*
G01X265961Y702125D01*
X265974Y702179D01*
G02X267059Y703717I2525J-629D01*
G03Y704383I-222J333D01*
G02Y708717I1440J2167D01*
G03Y709383I-222J333D01*
G02Y713717I1440J2167D01*
G03Y714383I-222J333D01*
G02X269939I1440J2167D01*
G03Y713717I222J-333D01*
G02Y709383I-1440J-2167D01*
G03Y708717I222J-333D01*
G02Y704383I-1440J-2167D01*
G03Y703717I222J-333D01*
G02X269128Y699025I-1440J-2167D01*
G01X269074Y699012D01*
X251907Y681845D01*
X251893Y681799D01*
G02X247475Y681911I-2193J701D01*
G03X246805Y682092I-387J-102D01*
G01X243902Y679188D01*
Y635427D01*
X214800Y606326D01*
Y605610D01*
X209939Y600748D01*
X209223D01*
X183236Y574762D01*
Y574761D01*
X180074Y571598D01*
X158585D01*
X158534Y571650D01*
X157673D01*
X157646Y571641D01*
G02X156480Y571609I-644J2210D01*
G03X155990Y571220I-90J-390D01*
G01Y561617D01*
X162067Y555540D01*
X180802D01*
G03X181201Y555963I0J400D01*
G02X185797I2298J137D01*
G03X186196Y555540I399J-23D01*
G01X198145D01*
G02Y552560I1755J-1490D01*
G01X195087D01*
G03X194875Y551821I0J-400D01*
G02X195605Y548085I-1376J-2208D01*
G03X195671Y547543I323J-236D01*
G02X195511Y543432I-1672J-1994D01*
G03X195444Y542841I232J-326D01*
G02X191549Y539390I-1945J-1728D01*
G03X190949I-300J-264D01*
G02X189580Y538577I-1949J1723D01*
G03X189380Y537911I89J-390D01*
G02X189222Y534163I-1881J-1798D01*
G03Y533563I264J-300D01*
G02X185776I-1723J-1950D01*
G03Y534163I-264J300D01*
G02X186918Y538649I1723J1950D01*
G03X187118Y539315I-89J390D01*
G02X187276Y543063I1881J1798D01*
G03Y543663I-264J300D01*
G02X187059Y547347I1723J1950D01*
G03Y547879I-299J266D01*
G02X187623Y551821I1940J1734D01*
G03X187411Y552560I-212J339D01*
G01X160833D01*
X159462Y553932D01*
G03X158782Y553701I-283J-283D01*
G02X156201Y556282I-2282J299D01*
G03X156432Y556962I-52J397D01*
G01X153010Y560383D01*
Y585168D01*
X159579Y591737D01*
G03X159203Y592408I-283J282D01*
G02X162789Y595994I-1132J4718D01*
G03X163460Y595618I389J-93D01*
G01X164210Y596368D01*
Y750259D01*
X154536Y759933D01*
Y808034D01*
G03X153918Y808369I-400J0D01*
G02X151456Y812934I-1419J2181D01*
G03Y813666I-161J366D01*
G02X150776Y818000I1043J2384D01*
G03Y818600I-264J300D01*
G02Y822500I1723J1950D01*
G03Y823100I-264J300D01*
G02X153918Y827231I1723J1950D01*
G03X154536Y827566I218J335D01*
G01Y829509D01*
G03X154102Y829907I-400J0D01*
G02X152065Y830810I-202J2293D01*
G01X151117D01*
X122690Y802383D01*
Y562767D01*
X137710Y547747D01*
X137798Y547751D01*
G02X135599Y545552I101J-2300D01*
G01X135603Y545640D01*
X119710Y561533D01*
Y803617D01*
X149883Y833790D01*
X152235D01*
G02X154102Y834493I1665J-1590D01*
G03X154536Y834891I34J398D01*
G37*
G36*
G01X150515Y522572D02*
G02X150050Y519589I1485J-1759D01*
G03X149429Y519659I-338J-213D01*
G02X146172Y523682I-1839J1841D01*
G03X146133Y524374I-218J335D01*
G02X148718Y524518I1167J2326D01*
G03X148757Y523826I218J-335D01*
G02X149902Y522694I-1167J-2326D01*
G03X150515Y522572I355J184D01*
G37*
G36*
G01X771069Y324854D02*
G03X771124Y325427I-249J313D01*
G02X774141Y325003I1749J1497D01*
G03X774111Y324693I110J-167D01*
G02X774254Y324540I-1609J-1647D01*
G01X784333D01*
X790301Y330507D01*
G03X790237Y331125I-283J283D01*
G02X789744Y331560I1261J1926D01*
G01X787733D01*
X571883Y547410D01*
X373314D01*
G02X374027Y550390I-1315J1890D01*
G01X573117D01*
X787023Y336484D01*
G03X787704Y336734I283J283D01*
G02X788737Y338475I2295J-185D01*
G03X788801Y339093I-219J335D01*
G01X788183Y339710D01*
X786983D01*
X465289Y661404D01*
X407489D01*
X353483Y715411D01*
G03X352800Y715116I-283J-283D01*
G02X350565Y717351I-2301J-66D01*
G03X350860Y718034I12J400D01*
G01X340660Y728234D01*
Y783283D01*
X330729Y793213D01*
X330641Y793209D01*
G02X330241Y797791I-100J2300D01*
G03X330472Y798471I-52J397D01*
G01X329688Y799254D01*
X329600Y799250D01*
G02X331799Y801449I-101J2300D01*
G01X331795Y801361D01*
X408877Y724278D01*
X769350D01*
G02Y721300I1755J-1489D01*
G01X752878D01*
G03X752495Y720786I0J-400D01*
G02X751696Y718077I-2496J-736D01*
G03X751629Y717544I260J-303D01*
G02X747737Y714135I-2130J-1494D01*
G03X747138Y714068I-270J-295D01*
G02X743517Y717689I-2139J1482D01*
G03X743584Y718288I-228J329D01*
G02X743003Y720786I1915J1762D01*
G03X742620Y721300I-383J114D01*
G01X407643D01*
X333040Y795903D01*
X332836Y795699D01*
X332840Y795611D01*
G02Y795408I-2300J-101D01*
G01X332836Y795320D01*
X343638Y784517D01*
Y729468D01*
X373418Y699688D01*
G03X374041Y699761I283J283D01*
G02X377754Y700040I1958J-1211D01*
G01X748067D01*
X749317Y698790D01*
X753983D01*
X778083Y722890D01*
X780583D01*
X780741Y723048D01*
G03X780686Y723659I-283J283D01*
G02X783890Y726863I1313J1891D01*
G03X784501Y726808I328J228D01*
G01X789867Y732173D01*
X789825Y732292D01*
G02X789713Y733320I2174J757D01*
G03X789269Y733764I-397J47D01*
G02X791285Y735780I-270J2286D01*
G03X791729Y735336I397J-47D01*
G02X792836Y730905I271J-2286D01*
G01X792797Y730890D01*
X781817Y719910D01*
X779317D01*
X755217Y695810D01*
X748083D01*
X746833Y697060D01*
X377754D01*
G02X377210Y696592I-1755J1490D01*
G03X377137Y695969I210J-340D01*
G01X408723Y664384D01*
X466523D01*
X769659Y361247D01*
G03X770280Y361316I283J283D01*
G02X770538Y361658I2199J-1391D01*
G03Y362190I-299J266D01*
G02X774428Y365647I1940J1734D01*
G03X775028I300J264D01*
G02X778928I1950J-1723D01*
G03X779528I300J264D01*
G02X783931Y363055I1950J-1723D01*
G03X784330Y362522I377J-134D01*
G02X786201Y357974I148J-2598D01*
G03Y357374I264J-300D01*
G02X782755I-1723J-1950D01*
G03Y357974I-264J300D01*
G02X782025Y360793I1723J1950D01*
G03X781626Y361326I-377J134D01*
G02X779528Y362201I-148J2598D01*
G03X778928I-300J-264D01*
G02X775028I-1950J1723D01*
G03X774428I-300J-264D01*
G02X774418Y362190I-1930J1745D01*
G03Y361658I299J-266D01*
G02X773870Y357726I-1940J-1734D01*
G03X773801Y357105I214J-338D01*
G01X788217Y342690D01*
X789417D01*
X795390Y336717D01*
Y331383D01*
X785567Y321560D01*
X774254D01*
G02X771069Y324854I-1755J1490D01*
G37*
G36*
G01X810813Y294738D02*
G02X807933I-1440J-2167D01*
G03Y295404I-222J333D01*
G02X808162Y299874I1440J2167D01*
G03X808112Y300604I-186J354D01*
G02X807462Y305150I887J2446D01*
G03X807512Y305752I-236J323D01*
G02X810910Y305471I1861J1819D01*
G03X810860Y304869I236J-323D01*
G02X810210Y300747I-1861J-1819D01*
G03X810260Y300017I186J-354D01*
G02X810813Y295404I-887J-2446D01*
G03Y294738I222J-333D01*
G37*
G36*
G01X25884Y196957D02*
G02Y199043I-2384J1043D01*
G03X26616I366J161D01*
G02Y196957I2384J-1043D01*
G03X25884I-366J-161D01*
G37*
G36*
G01X928893Y113742D02*
G02X928513Y116784I-1894J1308D01*
G03X929105Y116858I263J302D01*
G02X931745Y117728I1894J-1308D01*
G03X932263Y118201I130J378D01*
G02X935270Y120919I2236J549D01*
G03X935789Y121407I135J377D01*
G02X937228Y119881I2210J643D01*
G03X936709Y119393I-135J-377D01*
G02X933753Y116572I-2210J-643D01*
G03X933235Y116099I-130J-378D01*
G02X929485Y113816I-2236J-549D01*
G03X928893Y113742I-263J-302D01*
G37*
G36*
G01X37894Y117744D02*
G02X34970Y113672I-894J-2444D01*
G03X34357Y113685I-312J-250D01*
G02X31420Y117810I-1957J1715D01*
G03X31406Y118556I-151J370D01*
G02X34330Y122628I894J2444D01*
G03X34943Y122615I312J250D01*
G02X37880Y118490I1957J-1715D01*
G03X37894Y117744I151J-370D01*
G37*
G36*
G01X207516Y106659D02*
G02X205611Y107849I-2017J-1109D01*
G03X205982Y108441I20J400D01*
G02X207887Y107251I2017J1109D01*
G03X207516Y106659I-20J-400D01*
G37*
G36*
G01X168676Y105290D02*
G02X167422Y103410I1323J-2241D01*
G03X166822Y103810I-396J56D01*
G02X168076Y105690I-1323J2241D01*
G03X168676Y105290I396J-56D01*
G37*
G36*
G01X944542Y74934D02*
G02X942456I-1043J-2384D01*
G03Y75666I-161J366D01*
G02X941983Y80165I1043J2384D01*
G03X942009Y80795I-233J325D01*
G02X944989I1490J1755D01*
G03X945015Y80165I259J-305D01*
G02X944542Y75666I-1516J-2115D01*
G03Y74934I161J-366D01*
G37*
G36*
G01X226542Y54934D02*
G02X224456I-1043J-2384D01*
G03Y55666I-161J366D01*
G02Y60434I1043J2384D01*
G03Y61166I-161J366D01*
G02X224312Y65865I1043J2384D01*
G03X224332Y66566I-183J356D01*
G02X226666I1167J1984D01*
G03X226686Y65865I203J-345D01*
G02X226542Y61166I-1187J-2315D01*
G03Y60434I161J-366D01*
G02Y55666I-1043J-2384D01*
G03Y54934I161J-366D01*
G37*
G36*
G01X66913Y486302D02*
X66911Y486244D01*
X66910Y486243D01*
G02X62290Y486368I-2310J57D01*
G01X62390Y489768D01*
G02X67012Y489710I2311J-68D01*
G01Y489666D01*
X66912Y486302D01*
X66913D01*
G37*
G36*
G01X29212Y454904D02*
Y454854D01*
G02Y454802I-2313J-26D01*
G01Y454761D01*
X29209Y454722D01*
G02X24590Y454715I-2310J129D01*
G01X24589Y454718D01*
X24582Y454782D01*
X24577D01*
X24540Y456121D01*
X24476Y458436D01*
X24481D01*
X24486Y458520D01*
G02X25098Y460065I2313J-23D01*
G02X25216Y460184I1701J-1568D01*
G03X25208Y460722I-300J265D01*
G02X24175Y462656I1278J1926D01*
G01X24188Y466258D01*
G02X28782Y466613I2311J-9D01*
G03X29262Y466384I369J155D01*
G02X30154Y466510I892J-3097D01*
G01X64580D01*
G03X68086Y467962I0J4958D01*
G01X74119Y473995D01*
X77759Y477634D01*
G03X77393Y478300I-293J273D01*
G02X76354Y478204I-1041J5597D01*
G01X31040D01*
G03X30786Y478099I0J-360D01*
G02X30389Y477763I-2212J2210D01*
G02X28124Y476982I-2453J3439D01*
G02X23986Y478372I-1825J1422D01*
G01X23983Y478549D01*
X23981D01*
X23993Y478734D01*
X23992D01*
X24206Y482088D01*
X24231Y482161D01*
G02X25157Y483671I2285J-362D01*
G02X26143Y484081I1357J-1873D01*
G02X28796Y482182I372J-2283D01*
G03X29336Y481916I386J103D01*
G02X31039Y482258I1704J-4072D01*
G01X76352D01*
G03X77511Y482738I0J1639D01*
G01X113678Y518904D01*
X113679D01*
X113911Y519137D01*
G03X114424Y520376I-1239J1239D01*
G01Y807002D01*
G02X115724Y810139I4440J-2D01*
G01X117860Y812275D01*
G03X120673Y819233I-7194J6956D01*
G01Y819283D01*
X120674Y819287D01*
Y1036166D01*
G02X123415Y1042784I9363J-1D01*
G01X127090Y1046459D01*
G03X127372Y1047140I-681J681D01*
G01Y1047776D01*
X126699Y1048450D01*
X124739D01*
X124681Y1048441D01*
X124667Y1048437D01*
G02X121688Y1050650I-668J2213D01*
G01Y1054051D01*
G02X125267Y1055983I2311J-1D01*
G01X125317Y1055950D01*
X126000D01*
Y1055500D01*
X127249D01*
X128567Y1054182D01*
X128605Y1054166D01*
G02X130050Y1053213I-1606J-4006D01*
G02X130088Y1053174I-1002J-1015D01*
G02X131426Y1049894I-3354J-3281D01*
G01Y1047141D01*
G02X130885Y1044876I-5016J1D01*
G01X130820Y1044747D01*
X130965Y1044601D01*
X126282Y1039917D01*
G03X124726Y1036163I3754J-3755D01*
G01Y819231D01*
G02X120609Y809291I-14059J1D01*
G01X118591Y807273D01*
G03X118478Y807000I273J-273D01*
G01Y520374D01*
G02X118374Y519283I-5806J3D01*
G03X119039Y518915I393J-75D01*
G01X144460Y544336D01*
G03X145212Y546150I-1814J1815D01*
G01Y552415D01*
G02X144598Y553375I1628J1718D01*
G02X144473Y554121I2241J759D01*
G02X144472Y554127I1401J237D01*
G01Y555481D01*
G02X145212Y557189I2367J-11D01*
G01Y558075D01*
G02X144599Y559031I1627J1718D01*
G02X144473Y559781I2240J762D01*
G02X144472Y559787I1401J237D01*
G01Y561141D01*
G02X145212Y562848I2367J-12D01*
G01Y563735D01*
G02X144599Y564691I1627J1718D01*
G02X144473Y565441I2240J762D01*
G02X144472Y565447I1401J237D01*
G01Y566801D01*
G02X145212Y568508I2367J-12D01*
G01Y569395D01*
G02X144598Y570355I1628J1718D01*
G02X144473Y571101I2241J759D01*
G02X144472Y571107I1401J237D01*
G01Y572461D01*
G02X145212Y574169I2367J-11D01*
G01Y579582D01*
G02X144598Y580540I1627J1719D01*
G02X144473Y581288I2241J759D01*
G02X144472Y581294I1401J237D01*
G01Y582648D01*
G02X145212Y584355I2367J-12D01*
G01Y585242D01*
G02X144598Y586200I1627J1719D01*
G02X144473Y586948I2241J759D01*
G02X144472Y586954I1401J237D01*
G01Y588308D01*
G02X145212Y590015I2367J-12D01*
G01Y598976D01*
X145389D01*
G02X146045Y600560I5685J-1426D01*
G02X146929Y601694I5029J-3009D01*
G01X150246Y605012D01*
X155700Y610467D01*
G03X156372Y612169I-1822J1703D01*
G01Y636036D01*
G03X155790Y637441I-1987J0D01*
G03X155190Y637853I-1406J-1405D01*
G03X154385Y638024I-807J-1817D01*
G01X151198D01*
G02X149022Y638607I0J4354D01*
G02X146844Y642378I2176J3771D01*
G01Y643780D01*
G03X146119Y644013I-400J0D01*
G02X141926Y645356I-1881J1343D01*
G01Y649131D01*
G02X144269Y651442I2311J0D01*
G03X144568Y652115I6J400D01*
G01X142016Y654667D01*
X137791Y658891D01*
G03X137294Y659232I-1164J-1164D01*
G03X136627Y659374I-669J-1505D01*
G01X129849D01*
G03X129597Y659320I2J-623D01*
G03X129409Y659191I252J-569D01*
G01X128957Y658739D01*
G03X128652Y658295I1039J-1041D01*
G03X128526Y657700I1345J-596D01*
G01Y654290D01*
G03X128609Y653900I964J1D01*
G03X128809Y653609I881J391D01*
G01X130219Y652199D01*
G02X131214Y650747I-3400J-3397D01*
G02X131626Y648800I-4394J-1947D01*
G01Y647497D01*
G03X131660Y647075I2671J3D01*
G03X131690Y646919I2636J426D01*
G01X132021Y646826D01*
G02X130779Y642374I-621J-2226D01*
G01X127434Y643309D01*
X127432Y643310D01*
G02X127420Y647788I567J2241D01*
G01X127570Y647827D01*
Y648799D01*
G03X127350Y649329I-749J0D01*
G01X125939Y650740D01*
G02X124470Y654288I3552J3549D01*
G01Y657703D01*
G02X126087Y661608I5528J-2D01*
G01X127551Y663072D01*
X127708Y662915D01*
X127836Y662975D01*
G02X129847Y663430I2013J-4224D01*
G01X136627D01*
G02X139389Y662716I-1J-5703D01*
G01X139520Y662643D01*
X139649Y662772D01*
X149822Y652599D01*
X149720Y652497D01*
X149805Y652362D01*
G02X150902Y648562I-6043J-3803D01*
G01Y642378D01*
G03X151199Y642080I298J0D01*
G01X154388D01*
G02X158660Y640311I-1J-6045D01*
G02X160430Y636037I-4275J-4274D01*
G01Y612171D01*
G02X158511Y607539I-6552J1D01*
G01X149798Y598825D01*
G03X149270Y597550I1276J-1275D01*
G01Y547517D01*
G03X149789Y547189I396J52D01*
G02X152618Y544098I711J-2189D01*
G03X152814Y543580I368J-157D01*
G01X831326Y219788D01*
X833386Y217729D01*
X833474Y217732D01*
G02X831676Y214132I102J-2300D01*
G03X831134Y214246I-330J-225D01*
G02X827715Y215529I-1217J1954D01*
G01X827689Y215613D01*
X151694Y538315D01*
X151613Y538282D01*
G02X151393Y538206I-861J2135D01*
G01X151318Y538184D01*
X151237Y538050D01*
X151253Y537973D01*
G02X147310Y539064I-2253J-473D01*
G01Y540488D01*
G03X146668Y540805I-400J-1D01*
G01X95396Y489533D01*
G03X95555Y488928I321J-239D01*
G02X95945Y488713I-1057J-2378D01*
G03X96544Y488913I222J333D01*
G02X97553Y485887I2455J-863D01*
G03X96954Y485687I-222J-333D01*
G02X95413Y484114I-2455J863D01*
G03X95279Y483448I140J-375D01*
G02X95319Y483409I-1796J-1882D01*
G03X95879I280J286D01*
G02X99422Y479600I1820J-1859D01*
G03Y479000I264J-300D01*
G02X95879Y475191I-1723J-1950D01*
G03X95319I-280J-286D01*
G02X91776Y479000I-1820J1859D01*
G03Y479600I-264J300D01*
G02X92585Y483986I1723J1950D01*
G03X92719Y484652I-140J375D01*
G02X92121Y485494I1780J1898D01*
G03X91516Y485653I-366J-162D01*
G01X70956Y465092D01*
G02X64583Y462452I-6374J6374D01*
G01X30478D01*
G02X28529Y461567I-2579J3090D01*
G02X28037Y460935I-2042J1082D01*
G03X28103Y460408I330J-226D01*
G02X28723Y459782I-1304J-1911D01*
G02X29105Y458684I-1924J-1285D01*
G01X29115Y458564D01*
X29121D01*
X29123Y458504D01*
X29120D01*
Y458500D01*
X29123D01*
X29166Y456954D01*
X29222Y454914D01*
X29212Y454904D01*
G37*
G36*
G01X28610Y387639D02*
Y383766D01*
X28604Y383678D01*
G02X23988Y383854I-2305J176D01*
G01Y387629D01*
G02X28610Y387639I2311J0D01*
G37*
G36*
G01X27809Y1372022D02*
Y1372020D01*
X27859Y1368514D01*
Y1368512D01*
G02X23256Y1368448I-2301J-66D01*
G01Y1368449D01*
X23206Y1371978D01*
Y1371979D01*
G02X27809Y1372022I2301J65D01*
G37*
G36*
G01X23543Y1166884D02*
G02X21457I-1043J-2384D01*
G03Y1167616I-161J366D01*
G02X23543I1043J2384D01*
G03Y1166884I161J-366D01*
G37*
G36*
G01X29828Y1671684D02*
X29865Y1671672D01*
X30305Y1671698D01*
G03X30638Y1672276I-25J399D01*
G02X34326Y1671671I2062J1024D01*
G03X34296Y1671139I283J-283D01*
G02X31766Y1667522I-1802J-1433D01*
G01X31729Y1667534D01*
X30122Y1667437D01*
X30087Y1667420D01*
G02X29828Y1671684I-987J2080D01*
G37*
G36*
G01X29122Y1663281D02*
X29147Y1663275D01*
X31337Y1663332D01*
X31361Y1663339D01*
G02X31477Y1658885I638J-2212D01*
G01X31452Y1658891D01*
X29262Y1658834D01*
X29238Y1658827D01*
G02X29122Y1663281I-638J2212D01*
G37*
G36*
G01X33059Y1642740D02*
X29660Y1642691D01*
G02X29593Y1647313I-34J2311D01*
G01X32993Y1647362D01*
G02X35334Y1645191I34J-2311D01*
G01X35336Y1645159D01*
X35337Y1645126D01*
G02X35332Y1644890I-2311J-69D01*
G01X35326Y1644830D01*
G02X33059Y1642740I-2301J221D01*
G37*
G36*
G01X31155Y1631649D02*
X31174Y1631629D01*
X33238Y1630410D01*
X33264Y1630403D01*
G02X31006Y1626583I-601J-2222D01*
G01X30987Y1626602D01*
X28927Y1627820D01*
X28901Y1627827D01*
G02X31155Y1631649I598J2223D01*
G37*
G36*
G01X31659Y1611312D02*
X29539D01*
X29513Y1611305D01*
G02Y1615743I-614J2219D01*
G01X29539Y1615736D01*
X31659D01*
X31685Y1615743D01*
G02Y1611305I614J-2219D01*
G01X31659Y1611312D01*
G37*
G36*
G01X29780Y1518460D02*
X29788Y1518486D01*
Y1520860D01*
X29780Y1520886D01*
G02X34218I2219J614D01*
G01X34210Y1520860D01*
Y1518486D01*
X34218Y1518460D01*
G02X29780I-2219J-614D01*
G37*
G36*
G01X112930Y1132294D02*
G03X113490Y1132261I297J268D01*
G02X116947Y1128371I1710J-1961D01*
G03X116920Y1127805I268J-296D01*
G02X116939Y1124316I-1921J-1755D01*
G03Y1123784I299J-266D01*
G02Y1120316I-1940J-1734D01*
G03Y1119784I299J-266D01*
G02X113265Y1116110I-1940J-1734D01*
G03X112733I-266J-299D01*
G02X109059Y1119784I-1734J1940D01*
G03Y1120316I-299J266D01*
G02Y1123784I1940J1734D01*
G03Y1124316I-299J266D01*
G02X109276Y1128000I1940J1734D01*
G03Y1128600I-264J300D01*
G02X112930Y1132294I1723J1950D01*
G37*
G36*
G01X99276Y1097000D02*
G03Y1097600I-264J300D01*
G02X102295Y1101806I1723J1950D01*
G03X102828Y1101933I199J347D01*
G02X106307Y1102750I2172J-1433D01*
G03X106876Y1102941I200J346D01*
G02X108031Y1099961I2123J-891D01*
G03X107482Y1099718I-168J-363D01*
G02X106352Y1098277I-2482J782D01*
G03Y1097593I207J-342D01*
G02X103421Y1093302I-1346J-2227D01*
G03X102888Y1093260I-243J-317D01*
G02X99276Y1097000I-1889J1790D01*
G37*
G36*
G01X135770Y1079097D02*
G03Y1079633I-297J268D01*
G02X139188Y1079637I1707J1544D01*
G03Y1079101I297J-268D01*
G02X135770Y1079097I-1707J-1544D01*
G37*
G36*
G01X126734Y1081187D02*
Y1077435D01*
X126728Y1077347D01*
G02X122112Y1077523I-2305J176D01*
G01Y1081177D01*
G02X126734Y1081187I2311J0D01*
G37*
G36*
G01X88710Y937060D02*
Y936962D01*
X88704Y936874D01*
G02X84104Y936778I-2305J177D01*
G01X83704Y940156D01*
G02X88294Y940701I2295J272D01*
G01X88326Y940438D01*
X88694Y937322D01*
G02X88710Y937060I-2295J-272D01*
G37*
G36*
G01X98920Y890370D02*
G03X98947Y889684I218J-335D01*
G02X99223Y885291I-1247J-2284D01*
G03X99250Y884624I234J-325D01*
G02X96166Y880460I-1350J-2224D01*
G03X95634I-266J-299D01*
G02X92216Y884383I-1734J1940D01*
G03X92188Y885015I-259J305D01*
G02X92114Y889209I1502J2124D01*
G03X92088Y889864I-242J318D01*
G02X94993Y894180I1411J2186D01*
G03X95526Y894247I230J327D01*
G02X98920Y890370I1972J-1697D01*
G37*
G36*
G01X95942Y849978D02*
G03X95411Y850013I-285J-280D01*
G02X92351Y854219I-1603J2050D01*
G03X92376Y854862I-224J331D01*
G02X92410Y858954I1625J2033D01*
G03X92316Y859641I-245J316D01*
G02X95119Y863909I983J2409D01*
G03X95679I280J286D01*
G02X99066Y859973I1820J-1859D01*
G03X99133Y859293I241J-320D01*
G02X99248Y854666I-1132J-2343D01*
G03X99221Y853980I191J-351D01*
G02X95942Y849978I-1422J-2180D01*
G37*
G36*
G01X107322Y1078271D02*
G02X105075Y1077663I-605J-2221D01*
G03X104895Y1078329I-285J280D01*
G02X107142Y1078937I605J2221D01*
G03X107322Y1078271I285J-280D01*
G37*
G36*
G01X104860Y986959D02*
G02X102818Y987634I-1660J-1595D01*
G03X103040Y988305I-67J394D01*
G02X105082Y987630I1660J1595D01*
G03X104860Y986959I67J-394D01*
G37*
G36*
G01X89192Y1346587D02*
Y1342906D01*
G02X84588I-2302J-46D01*
G01Y1346589D01*
G02X89192I2302J46D01*
G01Y1346587D01*
G37*
G36*
G01X34021Y1460372D02*
X30485Y1460209D01*
G02X30272Y1464827I-106J2309D01*
G01X33809Y1464990D01*
G02X36208Y1462390I106J-2309D01*
G01X36203Y1462355D01*
G02X34021Y1460372I-2288J326D01*
G37*
G36*
G01X114785Y1358204D02*
X114720Y1357817D01*
G02X110160Y1358576I-2280J380D01*
G01X110719Y1361930D01*
G02X115310Y1361560I2280J-379D01*
G01Y1361550D01*
X115311D01*
G02Y1361545I-2312J-3D01*
G01X115310Y1361544D01*
Y1361460D01*
X115304Y1361374D01*
G02X115279Y1361170I-2305J179D01*
G01X114785Y1358204D01*
G37*
G54D21*
X895669Y1975079D03*
Y1801851D03*
Y1569567D03*
Y1396339D03*
Y1164055D03*
Y990827D03*
Y758543D03*
Y585315D03*
Y353031D03*
Y179803D03*
X167323Y1975079D03*
Y1801851D03*
Y1569567D03*
Y1396339D03*
Y1164055D03*
Y585315D03*
Y353031D03*
X68898Y595787D03*
Y422559D03*
Y190275D03*
Y17047D03*
G54D27*
X24000Y188500D03*
X30000D03*
X23500Y179000D03*
X30000D03*
X35000Y198500D03*
X36500Y188500D03*
Y179000D03*
X94500Y456800D03*
X58999Y1958050D03*
X82499Y1957050D03*
X73499D03*
X66499D03*
X92499Y1959050D03*
X47499Y1915050D03*
X62999Y1914550D03*
Y1926050D03*
X81499Y1915550D03*
X47499Y1930550D03*
X62499Y1939550D03*
X73499Y1945550D03*
X83999Y1945050D03*
X167499Y43550D03*
X116400Y56000D03*
X129100Y55900D03*
X127499Y65050D03*
X141999Y65550D03*
X156499Y66050D03*
X129999Y78050D03*
X127999Y99550D03*
X114800Y68500D03*
X155999Y181050D03*
X129400Y426900D03*
X137100Y436800D03*
X135999Y472550D03*
X135140Y478930D03*
X100500Y456700D03*
X149700Y471600D03*
X154100Y476500D03*
X164600Y476700D03*
X171300D03*
X145649Y509550D03*
X136349Y509050D03*
X161999Y768050D03*
X159186Y946117D03*
X126500Y1972400D03*
X119499Y1972550D03*
X119999Y1978550D03*
X126600Y1978500D03*
X199999Y46050D03*
X208499Y45650D03*
X225499Y46550D03*
X183499Y45550D03*
X192499Y57550D03*
X260999Y1503550D03*
X180000Y1619600D03*
X226999Y1941050D03*
X307999Y78550D03*
X305998Y352114D03*
X266999Y1512550D03*
X334999Y1797050D03*
X326301Y1766030D03*
X563499Y1503550D03*
X544300Y1784638D03*
X633837Y1807384D03*
X748000Y357500D03*
X751499Y679148D03*
X750000Y755500D03*
X747000Y1159000D03*
X757500Y1522500D03*
X717000Y1812384D03*
X750000Y1965500D03*
X840499Y55050D03*
X839999Y46050D03*
X840999Y62550D03*
X837999Y91050D03*
X838499Y99550D03*
Y107050D03*
X839499Y119050D03*
X841499Y71550D03*
X799385Y761436D03*
X767159Y1792364D03*
X767999Y1923050D03*
X773999Y1923550D03*
X916499Y36050D03*
X909999Y35550D03*
X902499Y35050D03*
X909499Y21550D03*
X917499D03*
X902999Y22050D03*
X854499Y39550D03*
X865499D03*
X883999Y39050D03*
X904999Y67550D03*
X855499Y82050D03*
X876999D03*
X867499D03*
X845999Y111050D03*
X865499Y125550D03*
X875499D03*
X856499Y71050D03*
X881499Y70550D03*
X866999D03*
X904499Y74050D03*
X903999Y574378D03*
X866499Y724550D03*
X873499Y1356050D03*
X904814Y1789113D03*
X864414Y1940050D03*
X929999Y32550D03*
X943499Y48050D03*
Y55050D03*
X22500Y1176500D03*
Y1183000D03*
G54D26*
X8499Y1937550D03*
X11703Y1951946D03*
X15750Y102250D03*
X45800Y405200D03*
X26199Y547176D03*
X36499Y566350D03*
X42599Y567850D03*
X25581Y567763D03*
X81251Y607249D03*
Y619251D03*
X95499Y1665418D03*
X93999Y1703050D03*
X85599Y1797350D03*
X86649Y1817100D03*
X80999Y1836550D03*
X40500Y1863000D03*
X15099Y1944050D03*
X50499Y1961550D03*
X14999Y1936050D03*
X17499Y1961050D03*
X43462Y1961160D03*
X32999Y1960555D03*
X25499Y1956050D03*
X42499Y1902550D03*
X48499Y1897050D03*
X57999Y1891050D03*
X31799Y1979050D03*
X97499Y90050D03*
X175499Y86572D03*
X176399Y94872D03*
X165500Y416500D03*
X159600Y446399D03*
X163549Y517100D03*
X171722Y513827D03*
X135499Y517550D03*
X107499Y497050D03*
X172499Y491053D03*
X176799Y493850D03*
X138416Y553500D03*
X110500Y790200D03*
X110499Y834550D03*
X108200Y963600D03*
X153499Y918550D03*
X172000Y961000D03*
X152500Y960000D03*
X170250Y948500D03*
X103999Y1216863D03*
X103686Y1223863D03*
X148000Y1206000D03*
X127000Y1202000D03*
X106162Y1205702D03*
X123970Y1221573D03*
X119399Y1298113D03*
X101541Y1262607D03*
X116999Y1288050D03*
X101399Y1292550D03*
X135850Y1322250D03*
X100699Y1471050D03*
X106999Y1454450D03*
X98599Y1491350D03*
X171999Y1662250D03*
X117499Y1706050D03*
X118499Y1694050D03*
X99199Y1761899D03*
X99999Y1753575D03*
X141999Y1764550D03*
X110099Y1759875D03*
X101399Y1784700D03*
X97999Y1843050D03*
X186999Y99050D03*
X213499Y104650D03*
X223499Y108150D03*
X188999Y120800D03*
X233749Y110800D03*
X230749Y76300D03*
X237899Y107050D03*
X247800Y269700D03*
X225298Y281114D03*
X253871Y291410D03*
X220000Y516400D03*
X246800Y677100D03*
X254499Y697700D03*
X247500Y1085500D03*
X182500Y1275500D03*
X194700Y1385700D03*
X224750Y1483950D03*
X195000Y1645500D03*
X179999Y1644500D03*
X201499Y1781050D03*
X213138Y1952703D03*
X249499Y1928050D03*
X231999Y1914050D03*
X210999Y1942050D03*
X223436Y1890465D03*
X214999Y1909550D03*
X257499Y1911050D03*
X249600Y1896800D03*
X343499Y31650D03*
X308999Y87050D03*
X282800Y87500D03*
X297499Y97550D03*
X301249Y346050D03*
X279939Y728610D03*
X282500Y1135000D03*
X269500Y1135500D03*
X326500Y1550200D03*
X261999Y1516050D03*
X264499Y1964050D03*
X330500Y1966500D03*
X310499Y1957050D03*
X394199Y45050D03*
X371700Y85500D03*
X350499Y597300D03*
X402499Y1476850D03*
X353499Y1710450D03*
X348499Y1762050D03*
X385499Y1735050D03*
X757499Y1079550D03*
X757999Y1484050D03*
X750000Y1560500D03*
X733149Y1798634D03*
X732549Y1806634D03*
X733049Y1814134D03*
X707600Y1815600D03*
X758499Y1893550D03*
X837999Y219550D03*
X822100Y279500D03*
X827500Y274500D03*
X809940Y264940D03*
X780499Y330050D03*
X829800Y666650D03*
X808660Y667540D03*
X769999Y733050D03*
X825700Y1083100D03*
X807000Y1072900D03*
X803199Y1151850D03*
X804899Y1556950D03*
X827700Y1487600D03*
X809960Y1478040D03*
X828500Y1877800D03*
X800431Y1941193D03*
X802499Y1951550D03*
X802099Y1961950D03*
X834799Y1946950D03*
X792499Y1949050D03*
X794499Y1941050D03*
X782999Y1937050D03*
X907499Y131800D03*
X910999Y124550D03*
X916499Y172550D03*
X854400Y264600D03*
X842499Y280924D03*
X868799Y294750D03*
X865499Y288050D03*
X867899Y321550D03*
X868299Y336150D03*
X902999Y556050D03*
X852696Y671197D03*
X900499Y962100D03*
X900999Y979050D03*
X864499Y1128750D03*
X852333Y1077716D03*
X867523Y1542821D03*
X867199Y1535150D03*
X854327Y1477550D03*
X863699Y1501250D03*
X886439Y1717600D03*
X862800Y1712700D03*
X889800Y1711500D03*
X917499Y1796550D03*
X873300Y1740100D03*
X854814Y1883550D03*
X863699Y1906450D03*
X857099Y1917650D03*
X938499Y115550D03*
X961499Y93350D03*
X926999Y122050D03*
X8750Y1086250D03*
X29000Y896500D03*
X21817Y1156317D03*
X25000Y1357742D03*
X25521Y1563350D03*
X21600Y1702900D03*
X94999Y901550D03*
X112699Y1058974D03*
X104600Y980500D03*
X120749Y1093990D03*
X132499Y1094550D03*
X125900Y1091282D03*
X101499Y1072550D03*
X105999Y1085800D03*
X123999Y1102550D03*
X116700Y1063500D03*
X105600Y1069500D03*
G54D23*
X78150Y28858D03*
Y178464D03*
Y434370D03*
Y583976D03*
X158071Y191614D03*
Y341220D03*
Y746732D03*
Y1002638D03*
Y1152244D03*
Y1408150D03*
Y1557756D03*
Y1813662D03*
Y1963268D03*
X886417Y191614D03*
Y341220D03*
Y597126D03*
Y746732D03*
Y1002638D03*
Y1152244D03*
Y1408150D03*
Y1557756D03*
Y1813662D03*
Y1963268D03*
G54D22*
X9843Y153168D03*
Y265767D03*
Y353144D03*
Y1859468D03*
G54D24*
X1019291Y1416024D03*
G54D25*
X17720Y1903144D03*
X29532Y309561D03*
X271657Y267711D03*
Y673223D03*
Y1078734D03*
Y1484246D03*
Y1889758D03*
X994098Y149601D03*
Y673223D03*
X994099Y1068892D03*
G54D28*
X994093Y1889751D03*
%LPD*%
G75*
G36*
G01X156499Y23050D02*
X142999Y36550D01*
X105499D01*
X94499Y47550D01*
X84999D01*
X82999Y49550D01*
Y55050D01*
X84499Y56550D01*
X92859D01*
G03X95139I1140J2000D01*
G01X100999D01*
X112999Y44550D01*
X146999D01*
X160499Y31050D01*
X272999D01*
X286499Y44550D01*
X289499D01*
X292499Y41550D01*
Y36550D01*
X278999Y23050D01*
X156499D01*
G37*
G36*
G01X279499Y21550D02*
X306999Y49050D01*
X312499D01*
X315999Y45550D01*
Y41550D01*
X284499Y10050D01*
X149499D01*
X139489Y20060D01*
X139476Y20113D01*
G03X123073Y24800I-9556J-2397D01*
G01X95749D01*
X79499Y41050D01*
Y45550D01*
X80499Y46550D01*
X84300D01*
X84501Y46348D01*
X93200D01*
X104249Y35300D01*
X141749D01*
X155499Y21550D01*
X279499D01*
G37*
G36*
G01X209455Y894795D02*
X209450Y894707D01*
G03X211851Y892300I2300J-107D01*
G01X211939Y892304D01*
X213233Y891010D01*
X213240D01*
X214200Y890050D01*
X224499D01*
X225999Y888550D01*
Y884050D01*
X223499Y881550D01*
X204999D01*
X157999Y928550D01*
X151999D01*
X148999Y931550D01*
Y936550D01*
X150499Y938050D01*
X163699D01*
X163724Y938024D01*
X166226D01*
X168834Y935416D01*
X168820Y935318D01*
G03X169931Y933017I2280J-318D01*
G02X170003Y932745I-101J-172D01*
G03X173663Y930009I1997J-1144D01*
G02X174235Y930015I289J-277D01*
G01X209455Y894795D01*
G37*
%LPC*%
G75*
G54D26*
X200539Y890300D03*
X200799Y896600D03*
%LPD*%
G75*
G54D10*
X11999Y53550D03*
X11499Y34050D03*
X10000Y16500D03*
X11499Y142050D03*
X11999Y69050D03*
X6891Y161611D03*
X11302Y161500D03*
X7089Y166111D03*
X11500Y166000D03*
X9499Y301050D03*
Y281550D03*
X8999Y318550D03*
Y889550D03*
X8499Y979050D03*
X8999Y961550D03*
Y942050D03*
Y926550D03*
X8499Y907050D03*
X8999Y1060550D03*
Y1041050D03*
Y1025550D03*
X8499Y1006050D03*
X8999Y988550D03*
X8499Y1078050D03*
X6500Y1146000D03*
X13000Y1145500D03*
Y1151000D03*
X7000Y1151500D03*
X8799Y1302550D03*
X7499Y1282050D03*
X7999Y1264550D03*
X9399Y1347350D03*
X8299Y1320050D03*
X7099Y1717750D03*
X7199Y1731450D03*
X6099Y1753750D03*
X11299Y1850050D03*
X9099Y1881550D03*
X8499Y1979550D03*
X11500Y1987000D03*
X92999Y52050D03*
X90899Y14850D03*
X23499Y27050D03*
X50999Y21150D03*
Y47750D03*
X27799Y38450D03*
X25799Y64050D03*
X65499Y59050D03*
Y41550D03*
Y27050D03*
X40999Y42050D03*
Y27550D03*
X17600Y5604D03*
X36000D03*
X55700Y5900D03*
X73900Y6200D03*
X90900Y5800D03*
X88000Y36400D03*
X93000Y44900D03*
X92900Y39700D03*
X52499Y145050D03*
Y130550D03*
X59499Y108050D03*
Y90550D03*
Y76050D03*
X96184Y151065D03*
X71015Y123666D03*
X78165Y137116D03*
X95814Y136065D03*
X77165Y110799D03*
X15302Y161500D03*
X19500D03*
X15500Y166000D03*
X19198Y152000D03*
X19698Y166000D03*
X92899Y231450D03*
X48499Y228550D03*
X23999Y229050D03*
X52499Y162550D03*
X96184Y166065D03*
X23895Y238995D03*
X51099Y300050D03*
X90899Y309550D03*
X93199Y279650D03*
X84899Y289250D03*
X86899Y242750D03*
X75299Y261750D03*
X42999Y275650D03*
X48499Y260550D03*
Y243050D03*
X23999Y261050D03*
Y243550D03*
X52199Y342350D03*
X89899Y368350D03*
X94199Y325550D03*
X93499Y337450D03*
X95499Y355450D03*
X89999Y396450D03*
X39999Y359550D03*
Y342050D03*
Y327550D03*
X15499Y360050D03*
Y342550D03*
Y328050D03*
X75300Y454100D03*
X67300Y450200D03*
X68899Y445450D03*
X87599Y403950D03*
X76099Y414250D03*
X95399Y416350D03*
X89099Y426150D03*
X42299Y564150D03*
X62055Y561550D03*
X49555Y563550D03*
X75999Y556640D03*
X70800Y540300D03*
X52333Y641295D03*
X72599Y578236D03*
X39999Y576550D03*
X61099Y603236D03*
X93599Y581236D03*
X92599Y606236D03*
X93100Y571640D03*
X47800Y692800D03*
X53210Y701486D03*
X39899Y754850D03*
X39399Y768750D03*
X26399Y750850D03*
X79900Y791300D03*
X67999Y790400D03*
X53999Y791000D03*
X26799Y874550D03*
X26099Y891650D03*
X76399Y820450D03*
X70100Y818900D03*
X25699Y916150D03*
X25099Y942150D03*
X23899Y957950D03*
X93499Y897152D03*
X93000Y907165D03*
X77499Y921550D03*
X77002Y952079D03*
X76711Y948089D03*
X77499Y962152D03*
X83988Y934028D03*
X24799Y992250D03*
X33899Y1005950D03*
X86900Y981600D03*
X21500Y1122500D03*
Y1092500D03*
X17500D03*
X18000Y1145500D03*
X17500Y1150500D03*
X22447Y1223247D03*
X23200Y1209300D03*
X21299Y1300250D03*
X21799Y1282750D03*
X22321Y1231121D03*
X18099Y1343550D03*
X96000Y1369000D03*
X96100Y1384650D03*
X77166Y1353400D03*
X93316Y1351000D03*
X77165Y1327335D03*
X76499Y1507050D03*
Y1498050D03*
Y1512050D03*
Y1503050D03*
X76999Y1528050D03*
Y1519050D03*
X90999Y1628550D03*
Y1624550D03*
X91121Y1632549D03*
X86299Y1632550D03*
X85999Y1628550D03*
Y1624550D03*
X15299Y1723450D03*
X15399Y1708350D03*
X14899Y1736250D03*
X15299Y1753250D03*
X84099Y1737150D03*
X83599Y1744750D03*
X77165Y1759550D03*
X93499D03*
X94336Y1773113D03*
X78529Y1788113D03*
X38600Y1880200D03*
X31400Y1885200D03*
X30400Y1849650D03*
X23999Y1857950D03*
X27199Y1874350D03*
X52999Y1871550D03*
X57499Y1871050D03*
X36100Y1892200D03*
X79500Y1987500D03*
X61500D03*
X44500Y1987000D03*
X26500D03*
X55999Y1982550D03*
X96999Y49550D03*
X157299Y5150D03*
X107000Y6000D03*
X97800Y36000D03*
X96900Y40400D03*
X169300Y130300D03*
X178700Y129900D03*
X152999Y141050D03*
X123499Y149050D03*
X133999D03*
X142999Y141050D03*
X132999Y141550D03*
X176499Y140050D03*
X167499Y149550D03*
X144499Y149050D03*
X163499Y140050D03*
X160999Y149550D03*
X123499Y140050D03*
X177899Y199250D03*
X117500Y162300D03*
X124300Y167800D03*
X131799Y201950D03*
X142688Y218861D03*
X143110Y203861D03*
X135399Y277050D03*
X130799Y300250D03*
X158999Y259800D03*
X152808Y246341D03*
X166800Y240800D03*
X133000Y240500D03*
X157740Y273924D03*
X139399Y372350D03*
X167299Y369350D03*
X130099Y326150D03*
X134699Y356050D03*
X126099Y396150D03*
X152499Y395950D03*
X99399Y437450D03*
X124899Y409050D03*
X133499Y445050D03*
X128999Y445550D03*
X130000Y452000D03*
X108599Y557236D03*
X154099Y529236D03*
X101500Y536500D03*
X139200Y484300D03*
X134499Y488050D03*
X108900Y587600D03*
X162500Y623400D03*
X140000Y587700D03*
X140499Y600550D03*
X152400Y643300D03*
X140499Y626050D03*
X143999Y605550D03*
X170799Y689150D03*
X171999Y672450D03*
X131099Y700450D03*
X139099Y707150D03*
X152124Y651868D03*
X159054Y665400D03*
X110800Y772700D03*
X178899Y765250D03*
X172599Y774250D03*
X111299Y821050D03*
X172099Y877450D03*
X168499Y846713D03*
X173899Y846550D03*
X161999Y843550D03*
Y848050D03*
X156499Y846050D03*
X156999Y850050D03*
X158114Y883290D03*
X156499Y886950D03*
X151999Y936550D03*
X152499Y931550D03*
X109500Y901100D03*
X153299Y943750D03*
X106500Y943000D03*
X105300Y960300D03*
X169299Y956350D03*
X151300Y1049300D03*
X171499Y998650D03*
X156499Y985950D03*
X149499Y997650D03*
X162499Y1023550D03*
X163499Y1035050D03*
X158300Y1015000D03*
X141234Y1029885D03*
X140864Y1044885D03*
X159499Y1044579D03*
X165600Y1057428D03*
X137900Y1103400D03*
X139100Y1097100D03*
X169299Y1067150D03*
X168099Y1083550D03*
X167999Y1092850D03*
X143200Y1116300D03*
X134500Y1108100D03*
X171599Y1139950D03*
X167499Y1118550D03*
X167999Y1130550D03*
X133200Y1132100D03*
X164999Y1075550D03*
X159055Y1070400D03*
X106999Y1114960D03*
X145900Y1163200D03*
X163499Y1171650D03*
X151699Y1158550D03*
X144399Y1171150D03*
X150999Y1181150D03*
X141499Y1185550D03*
X151499Y1173050D03*
X121657Y1224604D03*
X120999Y1188050D03*
X111999D03*
X102999D03*
X128400Y1188600D03*
X104999Y1231050D03*
X100999Y1231032D03*
X120999Y1228550D03*
X120499Y1264550D03*
X126499D03*
X123938Y1267623D03*
X103499Y1305050D03*
X117149Y1267550D03*
X145999Y1353050D03*
X167499Y1389050D03*
X123500Y1360300D03*
X156999Y1397750D03*
X143199Y1412050D03*
X163499Y1433350D03*
X166799Y1409350D03*
X178200Y1393400D03*
X176599Y1447450D03*
X172299Y1465850D03*
X165499Y1453550D03*
X157915Y1420460D03*
X140799Y1435460D03*
X166799Y1487450D03*
X176299Y1500150D03*
X159054Y1476200D03*
X124999Y1616050D03*
Y1620050D03*
Y1629050D03*
Y1633050D03*
X119999Y1629050D03*
X120100Y1633100D03*
X122499Y1668550D03*
Y1672550D03*
X126562Y1670613D03*
X118999Y1670550D03*
X172499Y1714050D03*
X157500Y1797400D03*
X126599Y1789650D03*
X120299Y1796150D03*
X142144Y1801644D03*
X104417Y1791480D03*
X144499Y1745550D03*
X137999Y1747723D03*
X129999Y1747050D03*
X123499D03*
X117499Y1745050D03*
X97999Y1815050D03*
X104500Y1813400D03*
X173899Y1813250D03*
X177599Y1866750D03*
X168299Y1879850D03*
X168499Y1855550D03*
X127499Y1889050D03*
X126999Y1882550D03*
X111499Y1877550D03*
Y1882550D03*
X122999Y1883050D03*
X115999Y1882550D03*
X157999Y1840972D03*
X158000Y1825400D03*
X159054Y1881800D03*
X167200Y1868000D03*
X159054Y1855050D03*
X143491Y1856400D03*
X116499Y1877550D03*
X122999Y1889050D03*
X168899Y1960750D03*
X163599Y1892050D03*
X159173Y1935972D03*
X142499Y1905972D03*
X141499Y1895972D03*
X98000Y1987500D03*
X163500D03*
X146000D03*
X128500D03*
X115000Y1987000D03*
X246200Y65800D03*
X246000Y61300D03*
Y56500D03*
Y52100D03*
X245600Y43800D03*
X245500Y39100D03*
X247100Y47900D03*
X189499Y4550D03*
X206999Y5050D03*
X226499D03*
X241999D03*
X261499Y4550D03*
X246000Y70800D03*
X244900Y149100D03*
X244499Y136550D03*
Y122050D03*
X206899Y171650D03*
X190199Y178650D03*
X232400Y220700D03*
X210999Y221550D03*
X191999D03*
X249800Y248800D03*
X235399Y263350D03*
X201199Y266750D03*
X181299Y267350D03*
X217999Y250550D03*
X203499D03*
X185999D03*
X187199Y359050D03*
X223799Y365350D03*
X209199Y365050D03*
X181599Y396250D03*
X217599Y396450D03*
X258999Y396650D03*
X209999Y426150D03*
X237699Y426050D03*
X218499Y474850D03*
X251499Y446050D03*
X231999Y445550D03*
X251999Y462050D03*
X232499Y461550D03*
X209499Y412550D03*
X220000Y421000D03*
X232999Y414550D03*
X252499Y415050D03*
X244199Y483350D03*
X224299Y494650D03*
X242099Y511750D03*
X244999Y559550D03*
Y545050D03*
X220499Y560050D03*
Y545550D03*
X257499Y530050D03*
Y512550D03*
Y498050D03*
X205300Y508100D03*
X190499Y507513D03*
X257199Y640050D03*
X224999Y613450D03*
X256499Y609050D03*
Y591550D03*
Y577050D03*
X245000Y647000D03*
X244499Y632050D03*
X219999Y647050D03*
Y632550D03*
X207300Y639400D03*
X206499Y623550D03*
Y609050D03*
X181999Y641550D03*
Y624050D03*
Y609550D03*
X244999Y577050D03*
X220499Y577550D03*
X199199Y659150D03*
X234200Y668300D03*
X226399Y677550D03*
X212999Y677350D03*
X190399Y689050D03*
X182599Y688350D03*
X246500Y663300D03*
X218800Y668700D03*
X224099Y770250D03*
X209500Y759000D03*
X208799Y766750D03*
X214799Y774750D03*
X245599Y773450D03*
X234299Y773750D03*
X247099Y795050D03*
X227199D03*
X197099D03*
X254699Y807650D03*
X233799Y806350D03*
X208299Y805350D03*
X198199Y805950D03*
X190699Y778350D03*
X215999Y887550D03*
X220499D03*
X215499Y883550D03*
X244099Y857450D03*
X245199Y878050D03*
X232399Y886550D03*
X252899Y886350D03*
X252399Y838250D03*
X245399Y823550D03*
X217300Y816800D03*
X198499Y884113D03*
X245399Y907450D03*
X243899Y923650D03*
X242199Y938750D03*
X256199Y916250D03*
X254899Y929250D03*
X253499Y938050D03*
X252499Y948850D03*
X244199Y973250D03*
X225299Y957650D03*
X213999Y958650D03*
X206699Y953050D03*
X203999Y943350D03*
X204699Y929450D03*
X205999Y978250D03*
X256499Y967050D03*
X233499Y966050D03*
X216999Y967550D03*
X254499Y984550D03*
X245899Y995250D03*
X232299Y981950D03*
X206299Y990250D03*
X207299Y1008150D03*
X202100Y1028100D03*
X253999Y1052050D03*
X253499Y1038550D03*
X232499Y1038050D03*
X216499Y1053050D03*
X215999Y1039550D03*
X258999Y1011550D03*
X233999Y1012550D03*
Y997050D03*
X217999Y1012050D03*
X217499Y998550D03*
Y981050D03*
X199499Y1093850D03*
X209900Y1093600D03*
X249499Y1104150D03*
X260349Y1139200D03*
X214499Y1154250D03*
X223099Y1182750D03*
X210199Y1173450D03*
X204199Y1163850D03*
X208199Y1145850D03*
X180400Y1202800D03*
X201600Y1205900D03*
X220999Y1224350D03*
X242199Y1210050D03*
X242599Y1198350D03*
X232599Y1195750D03*
X247899Y1208650D03*
X251999Y1184550D03*
X212499Y1212550D03*
X181700Y1219900D03*
X212499Y1184550D03*
X196499Y1224550D03*
Y1215550D03*
Y1196550D03*
X202199Y1276850D03*
X202899Y1291450D03*
X179500Y1262000D03*
X179800Y1244100D03*
X196399Y1236650D03*
X221599Y1237250D03*
X222299Y1251850D03*
X229899Y1250550D03*
X216300Y1274800D03*
X234299Y1232650D03*
X261199Y1227950D03*
X250900Y1248500D03*
X242900Y1263000D03*
X232799Y1276150D03*
X254899Y1289950D03*
X241399Y1303250D03*
X211499Y1267050D03*
Y1258050D03*
Y1239050D03*
X195499Y1279050D03*
Y1270050D03*
Y1251050D03*
X239099Y1314150D03*
X252399Y1326350D03*
X219099Y1325950D03*
X226599Y1340250D03*
X207699Y1337950D03*
X195500Y1352500D03*
X213199Y1350050D03*
X227399Y1363050D03*
X234300Y1375700D03*
X217499Y1387450D03*
X249800Y1388400D03*
X245999Y1358050D03*
X246499Y1370050D03*
X245999Y1339050D03*
X208049Y1385550D03*
X258999Y1396950D03*
X230599Y1400250D03*
X217999Y1408850D03*
X204699Y1418350D03*
X203199Y1393250D03*
X201000Y1408500D03*
X180599Y1424050D03*
X180000Y1439500D03*
X204999Y1472650D03*
X250199Y1473550D03*
X226300Y1447800D03*
X230899Y1437350D03*
X238899Y1453750D03*
X259299Y1438750D03*
X227999Y1421550D03*
X212400Y1433700D03*
X194200Y1457900D03*
X244999Y1412550D03*
X245499Y1424550D03*
X181500Y1479000D03*
X202399Y1500750D03*
X208999Y1491250D03*
X247500Y1499000D03*
X248000Y1482000D03*
X212899Y1535550D03*
X230999D03*
X213399Y1500300D03*
X236999Y1535550D03*
X246200Y1617600D03*
X239400Y1624300D03*
X218000Y1614300D03*
X209200Y1624000D03*
X228999Y1637550D03*
X211999Y1568550D03*
X238300Y1575100D03*
X231499Y1575050D03*
X224499D03*
X217999Y1574550D03*
X211999D03*
X258700Y1645100D03*
X237400Y1663800D03*
X230600Y1670500D03*
X197600Y1694900D03*
X204400Y1688200D03*
X216601Y1684350D03*
X226800Y1684200D03*
X220100Y1691700D03*
X209901Y1691850D03*
X212000Y1701300D03*
X201801Y1701450D03*
X195001Y1708150D03*
X205200Y1708000D03*
X180701Y1716050D03*
X195500Y1717000D03*
X200600Y1663600D03*
X199900Y1670600D03*
X213000Y1672500D03*
X181900Y1675300D03*
X255699Y1722550D03*
X222700Y1710100D03*
X242999Y1658050D03*
X193499Y1674050D03*
X253999Y1676550D03*
X235499Y1697050D03*
X256499Y1710050D03*
X180000Y1731000D03*
X179701Y1724550D03*
X195000Y1725500D03*
X249199Y1743150D03*
X222499Y1743850D03*
X259499Y1760650D03*
X221499Y1760950D03*
X199699Y1761450D03*
X220799Y1791550D03*
X252199Y1793050D03*
X238699Y1801850D03*
X205199Y1801950D03*
X182299Y1801350D03*
X206900Y1726700D03*
X185999Y1746050D03*
X237999Y1730550D03*
X244999Y1755050D03*
X253899Y1813250D03*
X215299Y1813950D03*
X255999Y1855950D03*
X204399Y1855450D03*
X206999Y1867550D03*
X241199Y1867150D03*
X244700Y1878700D03*
X224800Y1867000D03*
X212399Y1885850D03*
X199599Y1879850D03*
X181099Y1885850D03*
X261499Y1825050D03*
X209999D03*
X192100Y1813500D03*
X228999Y1856050D03*
X241255Y1896055D03*
X205499Y1968650D03*
X183999Y1968150D03*
X190399Y1961250D03*
X207199Y1892850D03*
X191599Y1891550D03*
X238999Y1970550D03*
X232999Y1971050D03*
X227499D03*
X221300Y1971200D03*
X240900Y1979000D03*
X225199Y1978750D03*
X209699D03*
X188199Y1978250D03*
X254500Y1987500D03*
X236500D03*
X216999Y1987550D03*
X199000Y1987500D03*
X183000D03*
X199600Y1974900D03*
X289499Y39050D03*
X286603Y34928D03*
X278999Y5050D03*
X292999Y4550D03*
X310499Y5050D03*
X329999D03*
X306999Y55450D03*
X311299D03*
X315799Y55350D03*
X300700Y39400D03*
X304500Y44500D03*
X305100Y39700D03*
X294100Y28000D03*
X308900Y41000D03*
X308800Y46400D03*
X306100Y126500D03*
X332200Y94200D03*
X283599Y106250D03*
X274700Y131500D03*
X280999Y120050D03*
X343799Y204550D03*
X321799Y173950D03*
X343399Y161350D03*
X307199Y205550D03*
X317499Y192950D03*
X331499Y193250D03*
X262699Y208550D03*
X262299Y164050D03*
X280999Y152050D03*
X343999Y190050D03*
X337999Y219050D03*
X310499Y216550D03*
X290999Y216050D03*
X271999D03*
X325499Y249450D03*
X313199Y270350D03*
X297999Y245050D03*
X283499D03*
X265999D03*
X343499Y253550D03*
X337499Y282550D03*
X313000Y313900D03*
X316999Y312576D03*
X267498Y295114D03*
X276299Y376050D03*
X299899Y376650D03*
X328799Y372350D03*
X339399Y358050D03*
X289399Y395750D03*
X310999Y396250D03*
X338399Y395650D03*
X321748Y343299D03*
X277799Y338599D03*
X266699Y425050D03*
X336099Y417550D03*
X322099Y426850D03*
X338899Y433850D03*
X300899Y431850D03*
X328599Y442250D03*
X291599Y446150D03*
X266199Y472350D03*
X327900Y463200D03*
X306100Y462000D03*
X286999Y462050D03*
X272499Y445050D03*
X272999Y461050D03*
X269999Y415050D03*
X284499D03*
X303999Y415550D03*
X324999Y414550D03*
X277999Y545350D03*
X329999Y510450D03*
X298599Y501250D03*
X309399Y513450D03*
X321999Y533150D03*
X297599Y519350D03*
X340799Y512050D03*
X341399Y535850D03*
Y558950D03*
X331999Y555050D03*
Y540550D03*
X307499Y555550D03*
Y541050D03*
X281999Y529550D03*
Y512050D03*
Y497550D03*
X321999Y550550D03*
X297499Y551050D03*
X333499Y483050D03*
X312499Y484050D03*
X292999Y483550D03*
X321299Y565250D03*
X296199Y568550D03*
X320799Y582050D03*
X340299Y586550D03*
X342199Y613050D03*
X328599Y602450D03*
X302899Y607950D03*
X328499Y635650D03*
X317999Y627850D03*
X342099Y646350D03*
X280999Y608550D03*
Y591050D03*
Y576550D03*
X331999Y572550D03*
X307499Y573050D03*
X331999Y646550D03*
X307499Y647050D03*
X293999Y630550D03*
Y616050D03*
X269499Y631050D03*
Y616550D03*
X341899Y664950D03*
X342599Y678850D03*
X341399Y715050D03*
X330799Y712450D03*
X324599Y696150D03*
X297699Y681850D03*
X296399Y716950D03*
X308899Y705150D03*
X298399Y703450D03*
X331999Y678550D03*
Y661050D03*
X307499Y679050D03*
Y661550D03*
X293999Y648050D03*
X269499Y648550D03*
X268499Y701550D03*
X338099Y811650D03*
X307999Y803150D03*
X307899Y794550D03*
X287799Y794850D03*
X268099Y795450D03*
X275299Y806350D03*
X315000Y754500D03*
X338599Y821650D03*
X318999Y814350D03*
X338599Y840450D03*
X325599Y823950D03*
X283599Y857450D03*
X293899Y843850D03*
X304899Y856150D03*
X315199Y869450D03*
X323099Y885050D03*
X340099Y887350D03*
X330299Y871850D03*
X323799Y859850D03*
X313499Y847850D03*
X300199Y835250D03*
X288899Y820550D03*
X264999Y858450D03*
X280999Y843050D03*
Y827550D03*
X264999Y842550D03*
X264499Y829050D03*
X297499Y884050D03*
Y868550D03*
X281499Y883550D03*
X280999Y870050D03*
X265799Y901850D03*
X274299Y912950D03*
X310699Y943550D03*
X323499Y956950D03*
X329799Y970650D03*
X331099Y923650D03*
X322099Y913650D03*
X302499Y899050D03*
X321099Y899650D03*
X338399Y901050D03*
X340099Y910350D03*
X340399Y931250D03*
X340099Y952850D03*
X328099Y937250D03*
X315199Y925950D03*
X302199Y914650D03*
X287299Y901050D03*
X269599Y923950D03*
X267199Y935350D03*
X264799Y946850D03*
X263299Y959350D03*
X281099Y943550D03*
X278799Y956150D03*
X277599Y975250D03*
X290099Y948650D03*
X289399Y963350D03*
X288099Y971250D03*
X299399Y965950D03*
X298099Y977250D03*
X307999Y970650D03*
X272999Y965550D03*
X333099Y983450D03*
X285399Y982950D03*
X294699Y989550D03*
X306699Y981250D03*
X304399Y997550D03*
X320999Y997250D03*
X331299Y1017150D03*
X331599Y1028750D03*
X329599Y1040750D03*
X321299Y1012450D03*
Y1024750D03*
X318299Y1038750D03*
X329599Y1057050D03*
X317699Y1054650D03*
X299999Y1052350D03*
X289699Y1021750D03*
X298399Y1008150D03*
X287099Y1000150D03*
X306399Y1020750D03*
X303699Y1038050D03*
X304699Y1057050D03*
X287099Y1035050D03*
X275099Y1024750D03*
X262499Y995850D03*
X269999Y1052550D03*
Y1037050D03*
X274999Y1012050D03*
Y996550D03*
X272999Y981050D03*
X339599Y1081550D03*
X319999Y1066950D03*
X274900Y1115600D03*
X262499Y1129150D03*
X272999Y1102850D03*
X312299Y1093550D03*
X276299Y1134550D03*
X290699Y1122650D03*
X329299Y1098550D03*
X326599Y1112350D03*
X307999Y1142050D03*
X299499Y1113550D03*
Y1098050D03*
X283499Y1113050D03*
X282999Y1099550D03*
X332999Y1138550D03*
Y1123050D03*
X317999Y1137550D03*
X316499Y1124550D03*
X283299Y1144850D03*
X323999Y1153250D03*
X304499Y1156650D03*
X313499Y1170150D03*
X291399Y1174150D03*
X300699Y1185150D03*
X279799Y1191750D03*
X286599Y1203750D03*
X315408Y1202663D03*
X329799Y1182750D03*
X311999Y1213850D03*
X300699Y1227350D03*
X272999Y1214150D03*
X326649Y1218850D03*
X328999Y1200550D03*
X333349Y1307000D03*
X310299Y1240050D03*
X264800Y1261300D03*
X283799Y1249250D03*
X304699Y1265850D03*
X312499Y1280350D03*
X300499Y1305350D03*
X274299Y1276450D03*
X295399Y1292950D03*
X281099Y1302850D03*
X333349Y1288900D03*
Y1270500D03*
X327999Y1255050D03*
X326649Y1227850D03*
X333349Y1332800D03*
X311500Y1316300D03*
X264799Y1313850D03*
X286799Y1326450D03*
X297899Y1336150D03*
X298099Y1357250D03*
X265299Y1339650D03*
X263699Y1359550D03*
X301699Y1377950D03*
X278799Y1386250D03*
X265499Y1376950D03*
X343599Y1360050D03*
X344399Y1338150D03*
X313600Y1391300D03*
X312900Y1366900D03*
X333349Y1363500D03*
X311900Y1344900D03*
X286499Y1364050D03*
Y1345050D03*
X301699Y1395750D03*
X268499Y1453550D03*
X278000Y1422000D03*
X270599Y1408550D03*
X303499Y1411250D03*
X300899Y1433350D03*
X286600Y1449700D03*
X304699Y1457550D03*
X344099Y1449550D03*
Y1421150D03*
Y1393750D03*
X313600Y1442700D03*
X312800Y1467400D03*
X333349Y1429500D03*
X312100Y1420700D03*
X285499Y1418550D03*
Y1427550D03*
Y1399550D03*
X333349Y1393100D03*
Y1481900D03*
X332500Y1519700D03*
X296599Y1497150D03*
X312000Y1514600D03*
X286700Y1516100D03*
X307000Y1619600D03*
X344500Y1583600D03*
X337199Y1636350D03*
X278499Y1621550D03*
X265700Y1635100D03*
X289000Y1641800D03*
X320299Y1642950D03*
X316799Y1657450D03*
X302399Y1662950D03*
X284300Y1676900D03*
X334399Y1691650D03*
X329999Y1716950D03*
X291099Y1707450D03*
X335767Y1662735D03*
X318499Y1675550D03*
X299999Y1696050D03*
X270999Y1660550D03*
X273499Y1694050D03*
X280499Y1718550D03*
X320999Y1706050D03*
X303999Y1722050D03*
X343899Y1752650D03*
X297099Y1733850D03*
X270599Y1748950D03*
X290699Y1760750D03*
X286599Y1791850D03*
X327299D03*
X322299Y1802150D03*
X303999Y1800850D03*
X270599Y1801450D03*
X263499Y1734550D03*
X285499Y1742550D03*
X321999Y1733050D03*
X303499Y1753550D03*
X321499Y1772550D03*
X315499Y1812250D03*
X284299Y1811150D03*
X270299Y1867250D03*
X337499Y1855950D03*
X316999D03*
X298999D03*
X308099Y1880550D03*
X295299Y1870250D03*
X313599Y1889250D03*
Y1870250D03*
X326399Y1876250D03*
X336799Y1888950D03*
Y1869950D03*
X283999Y1856050D03*
X314099Y1901250D03*
X326899Y1907250D03*
X326399Y1895250D03*
X335799Y1916450D03*
X336799Y1897950D03*
X305999Y1913050D03*
X302499Y1922050D03*
X296858Y1956228D03*
X326799Y1977050D03*
X329999Y1987550D03*
X311500Y1987500D03*
X291499Y1987550D03*
X272000Y1987500D03*
X416999Y25050D03*
X417499Y46550D03*
X416999Y63550D03*
X345499Y5050D03*
X364999Y4550D03*
X382499Y5050D03*
X395999Y5550D03*
X413499Y6050D03*
X381299Y136750D03*
X389599Y90950D03*
X400499Y134050D03*
Y119550D03*
X363999Y136050D03*
X417499Y79050D03*
Y93550D03*
Y108050D03*
Y125550D03*
X416999Y145050D03*
X387599Y220150D03*
X385999Y207250D03*
X354099Y175350D03*
X389299Y161650D03*
X400499Y151550D03*
X363999Y153550D03*
X369999Y219050D03*
X382499Y190550D03*
X355499Y219050D03*
X362999Y190050D03*
X416999Y164050D03*
X417999Y185050D03*
X423799Y259750D03*
X383299Y310250D03*
X386899Y299250D03*
X359399Y307250D03*
X347399Y301950D03*
X355999Y242750D03*
X347699Y269050D03*
X382999Y276650D03*
X412999Y307550D03*
Y290050D03*
Y275550D03*
X369499Y282550D03*
X381999Y254050D03*
X354999Y282550D03*
X362499Y253550D03*
X354099Y373050D03*
X368299Y386350D03*
X357999Y359050D03*
X380599Y381050D03*
X386599Y348450D03*
X394899Y357750D03*
X422499Y348150D03*
X422199Y363350D03*
X420199Y391350D03*
X419599Y458550D03*
X426599Y415350D03*
X415099Y422550D03*
X410799Y431150D03*
X354699Y426650D03*
X356399Y451750D03*
X351399Y470750D03*
X358399Y498650D03*
X357399Y521250D03*
Y530550D03*
Y543850D03*
X357999Y559450D03*
X415999Y518550D03*
X420199Y638550D03*
X427499Y624550D03*
X359399Y576050D03*
Y599650D03*
X360399Y615550D03*
X359699Y627550D03*
X345399Y698950D03*
X358899Y657150D03*
X359399Y669450D03*
X359199Y690650D03*
X357699Y707750D03*
X353999Y787750D03*
X347699Y773450D03*
X355999Y752850D03*
X424999Y766550D03*
X422999Y785050D03*
Y799550D03*
X418799Y896050D03*
Y877050D03*
X422499Y855550D03*
Y836550D03*
X422999Y817050D03*
X374500Y973500D03*
X375000Y939000D03*
Y1034000D03*
X424299Y1034050D03*
X423299Y1013050D03*
Y994050D03*
X373500Y1089500D03*
X419999Y1115550D03*
X409499Y1102550D03*
X416099Y1183550D03*
X415499Y1176050D03*
Y1161550D03*
X419499Y1219550D03*
X377499Y1210050D03*
Y1201050D03*
Y1182050D03*
X420099Y1241550D03*
X419499Y1234050D03*
X376599Y1293950D03*
X376499Y1264550D03*
Y1255550D03*
Y1236550D03*
X424999Y1278550D03*
X425499Y1290550D03*
X424999Y1259550D03*
X416699Y1342650D03*
X416199Y1367550D03*
X375599Y1323350D03*
X374499Y1375550D03*
Y1366550D03*
Y1347550D03*
X423299Y1430350D03*
X426799Y1416050D03*
X422299Y1394950D03*
X425799Y1447950D03*
X427099Y1469150D03*
X376299Y1437650D03*
X373099Y1456550D03*
X373499Y1430050D03*
Y1421050D03*
Y1402050D03*
X414799Y1532350D03*
X424299Y1541350D03*
X374099Y1554550D03*
X374799Y1491250D03*
X415999Y1603250D03*
X416199Y1625250D03*
X425499Y1635050D03*
X418299Y1561250D03*
X351899Y1570850D03*
X350600Y1610900D03*
X349099Y1634550D03*
X376099Y1572850D03*
X375099Y1608250D03*
X377700Y1629000D03*
X414799Y1653750D03*
X414399Y1678350D03*
X414499Y1707250D03*
X374999Y1656750D03*
X377099Y1696350D03*
X380099Y1709650D03*
X351099Y1691150D03*
X352000Y1700400D03*
X427499Y1662050D03*
X417799Y1790850D03*
X387899Y1802850D03*
X359499Y1736850D03*
X376799Y1734050D03*
X393499Y1759550D03*
X376499Y1775550D03*
X357999Y1796050D03*
X410757Y1772872D03*
X393999Y1784550D03*
X422999Y1778550D03*
X414499Y1810450D03*
X355699Y1810750D03*
X426499Y1855450D03*
X406999Y1855950D03*
X391499D03*
X369499D03*
X351999Y1855450D03*
X359999Y1878550D03*
X421399Y1888050D03*
X369799Y1880050D03*
X389499Y1885050D03*
X348999Y1879050D03*
X406499Y1874050D03*
X367299Y1956950D03*
X358999Y1925050D03*
X359999Y1897550D03*
Y1906550D03*
X420399Y1962550D03*
Y1934550D03*
Y1953550D03*
X421399Y1916050D03*
Y1907050D03*
X347699Y1972250D03*
X367999Y1940250D03*
X369199Y1919750D03*
X369999Y1901950D03*
X388499Y1959550D03*
Y1950550D03*
Y1932950D03*
X389499Y1913050D03*
Y1904050D03*
X349499Y1910050D03*
X348499Y1956550D03*
X347999Y1944550D03*
Y1925550D03*
X348999Y1898050D03*
X406999Y1905050D03*
X405999Y1951550D03*
X405499Y1939550D03*
Y1920550D03*
X406499Y1893050D03*
X385099Y1975950D03*
X420799Y1977250D03*
X399299Y1976750D03*
X367299Y1972950D03*
X420500Y1987000D03*
X403500D03*
X364999Y1987050D03*
X382499Y1987550D03*
X345499D03*
X436499Y50350D03*
Y31350D03*
X466799Y64750D03*
X465799Y43750D03*
Y24750D03*
X499999Y64050D03*
X500499Y47050D03*
X499999Y25550D03*
X432999Y6050D03*
X448499D03*
X467999Y5550D03*
X485499Y6050D03*
X498999D03*
X437499Y71350D03*
X442799Y142450D03*
X441799Y121450D03*
Y102450D03*
X471399Y124550D03*
X470399Y103550D03*
Y84550D03*
X473099Y141050D03*
X499999Y145550D03*
X500499Y126050D03*
Y108550D03*
Y79550D03*
Y94050D03*
X502899Y217150D03*
X504199Y193250D03*
X472999Y214550D03*
X483599Y179350D03*
X446799Y205650D03*
X445799Y184650D03*
Y165650D03*
X474099Y181050D03*
X473099Y160050D03*
X449999Y217050D03*
X430499D03*
X499999Y164550D03*
X466399Y304950D03*
X479299Y297250D03*
X437499Y307050D03*
Y289550D03*
Y275050D03*
X444499Y283050D03*
X463999Y283550D03*
X481499D03*
X495999D03*
X448999Y255550D03*
X469999Y254550D03*
X508499Y255050D03*
X488999Y254550D03*
X438999Y381550D03*
X458499Y382050D03*
X484900Y394700D03*
X485000Y373200D03*
X509999Y382550D03*
X443499Y354050D03*
X464499Y353050D03*
X502999Y353550D03*
X483499Y353050D03*
X498399Y470050D03*
X503699Y419250D03*
X472499Y458050D03*
X468799Y414250D03*
X443199Y440850D03*
X440099Y459250D03*
X431099Y479350D03*
X450300Y404200D03*
X490499Y464050D03*
X490999Y444550D03*
Y427050D03*
Y412550D03*
X454499Y472550D03*
X454999Y438550D03*
X454499Y458050D03*
X453999Y417550D03*
X430099Y551450D03*
X485299Y534550D03*
X508699Y498950D03*
X471499Y493950D03*
X452499Y565050D03*
X456499Y518050D03*
X435499Y519050D03*
X491499Y504050D03*
X490499Y483050D03*
X453999Y509550D03*
X454499Y490050D03*
X504499Y598050D03*
Y580550D03*
Y566050D03*
X479999Y598550D03*
Y581050D03*
Y566550D03*
X509999Y640550D03*
X452499Y597050D03*
Y579550D03*
X427999Y597550D03*
Y580050D03*
Y565550D03*
X506599Y711650D03*
X487299Y716950D03*
X451099Y711650D03*
X450399Y672750D03*
X444799Y687350D03*
X509999Y672550D03*
Y655050D03*
X488499Y691050D03*
Y673550D03*
Y659050D03*
X463999Y691550D03*
Y674050D03*
Y659550D03*
X467699Y772750D03*
X468699Y788350D03*
X472999Y736550D03*
X489599Y752450D03*
X490299Y734550D03*
X453399Y807950D03*
X452099Y781450D03*
Y762450D03*
X435299Y795150D03*
Y777650D03*
Y763150D03*
X437299Y744650D03*
X495999Y795050D03*
X475699Y880450D03*
X479599Y847550D03*
X462999Y884050D03*
Y865050D03*
X453399Y826950D03*
X434799Y833650D03*
Y814650D03*
X464499Y896050D03*
X493499Y884050D03*
Y865050D03*
X493999Y845550D03*
Y813550D03*
Y828050D03*
X506899Y919950D03*
Y900950D03*
X443599Y945650D03*
X442599Y924650D03*
Y905650D03*
X486799Y941050D03*
X485799Y920050D03*
Y901050D03*
X461999Y966050D03*
X462499Y946550D03*
Y914550D03*
Y929050D03*
X494099Y1017350D03*
X493099Y996350D03*
X462499Y1043850D03*
X461999Y985050D03*
X474499Y1115050D03*
X491999Y1115550D03*
X454999D03*
X439499D03*
X501499Y1102550D03*
X463999Y1102050D03*
X481499Y1102550D03*
X444499D03*
X428999D03*
X436999Y1142550D03*
Y1128050D03*
X504399Y1132250D03*
X473099Y1144550D03*
X453499Y1140550D03*
X484499Y1085850D03*
X483499Y1064850D03*
X433599Y1085550D03*
X432599Y1064550D03*
X463499Y1083850D03*
X462499Y1062850D03*
X437599Y1150050D03*
X487099Y1218050D03*
X486499Y1210550D03*
Y1196050D03*
X443199Y1224250D03*
X507199Y1224350D03*
X506599Y1202350D03*
Y1216850D03*
X505399Y1153250D03*
X474099Y1165550D03*
X454499Y1161550D03*
X443799Y1274250D03*
Y1246250D03*
Y1265250D03*
X443199Y1238750D03*
X507199Y1252350D03*
Y1243350D03*
X465499Y1284550D03*
Y1293550D03*
Y1265550D03*
X498299Y1323350D03*
X468999Y1323950D03*
X428499Y1325350D03*
X508599Y1370550D03*
X444899Y1377950D03*
X434499Y1360250D03*
X448099Y1341250D03*
X473999Y1342450D03*
X485599Y1367550D03*
X468699Y1362850D03*
X466699Y1378150D03*
X498899Y1386450D03*
X499199Y1350550D03*
X459699Y1468050D03*
X464199Y1401450D03*
X459999Y1424050D03*
X498899Y1408350D03*
X500899Y1434350D03*
X505899Y1466250D03*
X482599Y1449950D03*
X456399Y1445950D03*
X445099Y1464250D03*
X478299Y1464850D03*
X481499Y1417050D03*
Y1402550D03*
X441499Y1431550D03*
Y1414050D03*
Y1399550D03*
X499699Y1538950D03*
X466999Y1530650D03*
X488299Y1531050D03*
X461399Y1541650D03*
X474299Y1544750D03*
X452199Y1550650D03*
X444299Y1532650D03*
X439599Y1552150D03*
X465999Y1603450D03*
X487099Y1606250D03*
X449199Y1579050D03*
X443799Y1612250D03*
X460199Y1632850D03*
X484999Y1636550D03*
X501399Y1634550D03*
X508199Y1610450D03*
X510100Y1579800D03*
X472299Y1572050D03*
X502199Y1566250D03*
X472499Y1620550D03*
Y1611550D03*
X484200Y1579900D03*
X432499Y1617550D03*
X434500Y1579500D03*
X431999Y1605550D03*
X435300Y1715300D03*
X448399Y1699450D03*
X447699Y1682850D03*
X449599Y1656950D03*
X483599Y1662550D03*
X485599Y1694850D03*
X502899Y1709650D03*
X507399Y1683350D03*
X509199Y1660550D03*
X468499Y1712550D03*
X467999Y1687050D03*
Y1696050D03*
Y1668050D03*
X432400Y1680100D03*
X428600Y1691200D03*
X436799Y1772550D03*
X472699Y1792150D03*
X429499Y1748050D03*
X458499Y1742050D03*
X441499Y1758050D03*
X480999Y1756050D03*
X463999Y1772050D03*
X445499Y1792550D03*
X508200Y1758200D03*
X484999Y1779050D03*
X496999Y1799550D03*
X481299Y1811150D03*
X448099Y1809450D03*
X499999Y1854950D03*
X480499Y1855450D03*
X464999D03*
X443999Y1855950D03*
X476199Y1877450D03*
X434299Y1876050D03*
X446999Y1880050D03*
X492999Y1878050D03*
X504799Y1967550D03*
Y1939550D03*
Y1958550D03*
X505799Y1921050D03*
Y1912050D03*
Y1893050D03*
X475199Y1951950D03*
Y1923950D03*
Y1942950D03*
X476199Y1905450D03*
Y1896450D03*
X459299Y1966850D03*
Y1938850D03*
Y1957850D03*
X460299Y1920350D03*
Y1911350D03*
Y1892350D03*
X433299Y1950550D03*
Y1922550D03*
Y1941550D03*
X434299Y1904050D03*
Y1895050D03*
X445999Y1954550D03*
Y1945550D03*
Y1926550D03*
X446999Y1908050D03*
Y1899050D03*
X493499Y1909050D03*
X492499Y1955550D03*
X491999Y1943550D03*
Y1924550D03*
X492999Y1897050D03*
X509299Y1977250D03*
X493799D03*
X473299D03*
X455799Y1976750D03*
X436299Y1977250D03*
X492500Y1987500D03*
X476000Y1987000D03*
X456500Y1987500D03*
X438999Y1987550D03*
X522899Y64350D03*
Y45350D03*
X587999Y63550D03*
X588499Y46550D03*
X587999Y25050D03*
X541499Y63550D03*
X541999Y46550D03*
X541499Y25050D03*
X516499Y6550D03*
X535999D03*
X551499D03*
X570999Y6050D03*
X588499Y6550D03*
X523899Y85350D03*
X520299Y141450D03*
Y122450D03*
X569099Y112550D03*
X568099Y91550D03*
Y72550D03*
X562799Y146750D03*
Y127750D03*
X587999Y145050D03*
X588499Y125550D03*
X541499Y145050D03*
X541999Y125550D03*
Y108050D03*
Y79050D03*
Y93550D03*
X565999Y199950D03*
X528799D03*
X521299Y162450D03*
X563799Y167750D03*
X587999Y217050D03*
X568499Y217550D03*
X552999D03*
X533499D03*
X588999Y185050D03*
X587999Y164050D03*
X542499Y185050D03*
X541499Y164050D03*
X544799Y293950D03*
X540099Y306550D03*
X516899Y306950D03*
X515499Y284050D03*
X536499Y283050D03*
X525999Y255050D03*
X540499D03*
X572999Y287050D03*
X572499Y306550D03*
X572999Y269550D03*
Y255050D03*
X579899Y375750D03*
X530999Y381550D03*
X520499Y353550D03*
X548100Y362200D03*
X573499Y346550D03*
X572499Y325550D03*
X577899Y460550D03*
X578399Y441050D03*
X577399Y420050D03*
X539799Y466050D03*
X538799Y445050D03*
X576099Y481850D03*
X511299Y449150D03*
X519499Y471550D03*
X518999Y416550D03*
X592499Y478050D03*
Y459050D03*
X592999Y439550D03*
Y422050D03*
Y407550D03*
X556499Y467550D03*
X555999Y412550D03*
X539299Y485550D03*
X576599Y522350D03*
X577099Y502850D03*
X579499Y561550D03*
X558499Y562550D03*
X538999Y562050D03*
X535499Y545050D03*
X514499Y546050D03*
X518999Y508550D03*
X519499Y489050D03*
X555999Y504550D03*
X556499Y485050D03*
X534499Y640050D03*
X586299Y711250D03*
X565699Y710650D03*
X549999Y710050D03*
X547999Y728550D03*
X573499Y690550D03*
Y673050D03*
Y658550D03*
X534499Y672050D03*
Y654550D03*
Y805950D03*
X511199Y782050D03*
X527499Y747150D03*
X525499Y772450D03*
X547499Y799050D03*
Y780050D03*
X547999Y760550D03*
Y743050D03*
X575499Y802050D03*
X575999Y782550D03*
Y765050D03*
X577999Y732050D03*
X575999Y750550D03*
X526499Y851150D03*
X510899Y868150D03*
X578299Y895650D03*
X541399Y873450D03*
Y854450D03*
X512899Y842550D03*
Y823550D03*
X521999Y895550D03*
X522499Y876050D03*
X576499Y842050D03*
X575499Y821050D03*
X583299Y961450D03*
X578299Y914650D03*
X540299Y956850D03*
X539299Y935850D03*
X570899Y965850D03*
Y946850D03*
X521999Y914550D03*
X562999Y898050D03*
X560499Y968050D03*
X560999Y948550D03*
Y916550D03*
Y931050D03*
X516499Y957050D03*
X514499Y975550D03*
X583299Y980450D03*
X534599Y1048550D03*
X571899Y986850D03*
X573499Y1055550D03*
Y1036550D03*
X541899Y1021450D03*
X540899Y1000450D03*
Y981450D03*
X560499Y987050D03*
X560999Y999050D03*
X558999Y1049550D03*
Y1017550D03*
Y1032050D03*
X513999Y1046050D03*
Y1027050D03*
X514499Y1007550D03*
Y990050D03*
X588499Y1101550D03*
X578999Y1114550D03*
X568499Y1101550D03*
X564499Y1116050D03*
X548999D03*
X529499D03*
X511999Y1115550D03*
X553999Y1103050D03*
X538499D03*
X518999D03*
X535599Y1069550D03*
X574499Y1076550D03*
X558499Y1088050D03*
Y1069050D03*
X547099Y1202750D03*
Y1221750D03*
X546499Y1180750D03*
Y1195250D03*
X567999Y1215550D03*
Y1206550D03*
Y1187550D03*
X527999Y1212550D03*
X527499Y1200550D03*
Y1181550D03*
X579299Y1300750D03*
X527499Y1278150D03*
X530499Y1297050D03*
X561099Y1301050D03*
X566399Y1273850D03*
X549399Y1302850D03*
Y1274850D03*
Y1293850D03*
X548799Y1252850D03*
Y1267350D03*
X547099Y1230750D03*
X583299Y1283250D03*
Y1255250D03*
Y1274250D03*
X582699Y1233250D03*
Y1247750D03*
X565999Y1248550D03*
Y1234050D03*
X525999Y1263050D03*
Y1245550D03*
Y1231050D03*
X555699Y1322950D03*
X581999Y1370150D03*
X559099Y1343250D03*
X545099Y1355250D03*
X518499Y1346950D03*
X540399Y1382150D03*
X523999Y1391050D03*
X523499Y1360050D03*
Y1379050D03*
X580999Y1412750D03*
X575699Y1438950D03*
X538799Y1409750D03*
X536799Y1436350D03*
X528499Y1460250D03*
X546099Y1467550D03*
X582999Y1461250D03*
X557499Y1443050D03*
Y1452050D03*
Y1424050D03*
X516999Y1437050D03*
X517499Y1449050D03*
X516999Y1418050D03*
X590599Y1483450D03*
X529799Y1555050D03*
X567999Y1549950D03*
X582299Y1534150D03*
X538999Y1528350D03*
X518899Y1530150D03*
X532499Y1635550D03*
X552099Y1601950D03*
X553399Y1624550D03*
X590799Y1627850D03*
X588000Y1604000D03*
X588099Y1572050D03*
X552199Y1576650D03*
X569499Y1619550D03*
Y1610550D03*
X573400Y1577600D03*
X529499Y1616550D03*
X533800Y1575500D03*
X528999Y1604550D03*
X518499Y1643950D03*
X538299Y1721050D03*
X532599Y1655650D03*
X554199Y1651950D03*
X555199Y1674750D03*
X555399Y1689350D03*
X555899Y1706750D03*
X580299Y1722550D03*
X590599Y1694450D03*
X580799Y1646150D03*
X572999Y1694550D03*
Y1703550D03*
Y1675550D03*
X532499Y1688550D03*
X532999Y1700550D03*
X532499Y1669550D03*
X582599Y1740050D03*
X560399Y1792550D03*
X555500Y1802700D03*
X539499Y1788150D03*
X526499Y1801150D03*
X556199Y1727050D03*
X522300Y1739200D03*
X532499Y1763050D03*
X515499Y1779050D03*
X531799Y1818450D03*
X514199Y1815750D03*
X591499Y1855950D03*
X573999Y1855450D03*
X554499Y1855950D03*
X538999D03*
X517499Y1855450D03*
X588899Y1882350D03*
X562599Y1874450D03*
X519399Y1876750D03*
X533499Y1884050D03*
X575999Y1888050D03*
X587899Y1956850D03*
Y1928850D03*
Y1947850D03*
X588899Y1910350D03*
Y1901350D03*
X561599Y1948950D03*
Y1920950D03*
Y1939950D03*
X562599Y1902450D03*
Y1893450D03*
X546999Y1966850D03*
Y1938850D03*
Y1957850D03*
X547999Y1920350D03*
Y1911350D03*
Y1892350D03*
X518399Y1951250D03*
Y1923250D03*
Y1942250D03*
X519399Y1904750D03*
Y1895750D03*
X532499Y1958550D03*
Y1949550D03*
Y1930550D03*
X533499Y1912050D03*
Y1903050D03*
X575999Y1907050D03*
X576499Y1919050D03*
X574999Y1953550D03*
X575499Y1965550D03*
X574999Y1934550D03*
X585799Y1976250D03*
X570299D03*
X546299Y1977250D03*
X528799Y1976750D03*
X568999Y1987050D03*
X553499D03*
X588499Y1986550D03*
X511999Y1987550D03*
X531500Y1987500D03*
X603999Y54350D03*
Y35350D03*
X651799Y59650D03*
Y40650D03*
X674999Y59050D03*
X675499Y42050D03*
X674999Y20550D03*
X624499Y61550D03*
X624999Y44550D03*
X624499Y23050D03*
X608499Y6550D03*
X625999Y7050D03*
X645499D03*
X660999D03*
X604999Y75350D03*
X603999Y133750D03*
X652799Y80650D03*
X649899Y138350D03*
X674999Y140550D03*
X675499Y121050D03*
Y103550D03*
Y74550D03*
Y89050D03*
X624499Y143050D03*
X624999Y123550D03*
X623899Y202550D03*
X604999Y173750D03*
X603999Y152750D03*
X650899Y178350D03*
X649899Y157350D03*
X662499Y218050D03*
X642999D03*
X625499Y217550D03*
X605499D03*
X675999Y180550D03*
X674999Y159550D03*
X625499Y183050D03*
X624499Y162050D03*
X656499Y307050D03*
X653999Y286550D03*
X627999Y280050D03*
X627499Y299550D03*
X627999Y262550D03*
Y248050D03*
X599799Y385150D03*
X600299Y365650D03*
X599299Y344650D03*
X659899Y363250D03*
X632399Y358750D03*
X635399Y376250D03*
X607399Y380250D03*
X643599Y395950D03*
X655999Y344050D03*
X656499Y324550D03*
X628499Y339550D03*
X628200Y320000D03*
X644099Y450950D03*
X644599Y416950D03*
X644099Y436450D03*
X621499Y466550D03*
X621999Y432550D03*
X621499Y452050D03*
X620999Y411550D03*
X666999Y476550D03*
X643499Y546750D03*
X642499Y525750D03*
X613700Y504600D03*
X621499Y484050D03*
X593499Y499050D03*
X666499Y547050D03*
X666999Y508550D03*
X666499Y528050D03*
X666999Y491050D03*
X642999Y566250D03*
X640599Y604650D03*
X673999Y645150D03*
X645099Y639150D03*
X631999Y639650D03*
X665999Y623550D03*
X620499D03*
Y609050D03*
X595999Y641550D03*
Y624050D03*
Y609550D03*
X674999Y601550D03*
X646999Y584550D03*
X625999Y585050D03*
X606499Y584550D03*
X667499Y568050D03*
X651999Y718350D03*
X648999Y702350D03*
X629099Y714050D03*
X605299Y661750D03*
X609499Y708050D03*
X607499Y726550D03*
X647499Y689050D03*
Y671550D03*
Y657050D03*
X622999Y689550D03*
Y672050D03*
X597999Y690050D03*
X647399Y742150D03*
X653099Y803350D03*
X621499Y767150D03*
X633499Y750150D03*
X606999Y797050D03*
Y778050D03*
X607499Y758550D03*
Y741050D03*
X664999Y805050D03*
Y786050D03*
X665499Y766550D03*
X645799Y816650D03*
X642599Y883250D03*
X641599Y862250D03*
Y843250D03*
X621999Y835050D03*
X612999Y854550D03*
X629499Y853050D03*
Y868550D03*
X613499Y868050D03*
X663499Y896050D03*
X663999Y876550D03*
Y844550D03*
Y859050D03*
X665999Y826050D03*
X639499Y971150D03*
Y952150D03*
X616699Y967250D03*
Y948250D03*
X658999Y959050D03*
X656999Y977550D03*
X603499Y904050D03*
X601499Y954550D03*
Y922550D03*
Y937050D03*
X664499Y936050D03*
X663499Y915050D03*
X673999Y1036550D03*
Y1017550D03*
X674699Y1061450D03*
X611399Y1045650D03*
Y1026650D03*
X617699Y988250D03*
X656499Y1048050D03*
Y1029050D03*
X656999Y1009550D03*
Y992050D03*
X631999Y1001550D03*
X629999Y1052050D03*
Y1020050D03*
Y1034550D03*
X600999Y1002050D03*
X598999Y1052550D03*
Y1020550D03*
Y1035050D03*
X633999Y1103050D03*
X669499Y1116550D03*
X616499Y1115050D03*
X605999Y1102050D03*
X598999Y1114550D03*
X674699Y1080450D03*
X674999Y1134950D03*
X641799Y1137650D03*
X627699Y1143550D03*
X612399Y1066650D03*
X629499Y1090550D03*
Y1071550D03*
X598499Y1091050D03*
Y1072050D03*
X603899Y1157850D03*
X626199Y1183450D03*
X597599Y1196050D03*
X596599Y1215050D03*
X651599Y1203050D03*
X650599Y1182050D03*
X651299Y1174150D03*
X650299Y1153150D03*
X668199Y1173850D03*
X667199Y1152850D03*
X671199Y1213750D03*
X670199Y1192750D03*
X628699Y1164550D03*
X668699Y1227650D03*
X672999Y1303450D03*
X608899Y1305050D03*
X600899Y1238650D03*
X630499Y1243950D03*
X657099Y1272850D03*
X657799Y1288450D03*
X656399Y1307050D03*
X618199Y1296250D03*
Y1268250D03*
Y1287250D03*
X617599Y1246250D03*
Y1260750D03*
X638999Y1286550D03*
Y1295550D03*
Y1267550D03*
X598499Y1280550D03*
X598999Y1292550D03*
X598499Y1261550D03*
X671999Y1324950D03*
X631799Y1322650D03*
X605599Y1326350D03*
X665699Y1337250D03*
X606199Y1338250D03*
X617899Y1360850D03*
X625499Y1383450D03*
X632499Y1347950D03*
X599999Y1382550D03*
X599499Y1351550D03*
Y1370550D03*
X654999Y1385050D03*
X654499Y1373050D03*
Y1354050D03*
X659699Y1445950D03*
X604899Y1407750D03*
X601299Y1447650D03*
X636799Y1461250D03*
X626799Y1432350D03*
X627499Y1406050D03*
X665699Y1462250D03*
X652999Y1435550D03*
Y1418050D03*
Y1403550D03*
X656099Y1479550D03*
X625199Y1489150D03*
X610899Y1496750D03*
X672399Y1508750D03*
X673699Y1535350D03*
X662099Y1549650D03*
X643099Y1541350D03*
X599799Y1544650D03*
X617699Y1530350D03*
X670699Y1603150D03*
X671399Y1625350D03*
X628499Y1636650D03*
X633499Y1615450D03*
X635500Y1603900D03*
X652399Y1575850D03*
X623499Y1564050D03*
X652499Y1618550D03*
Y1609550D03*
X639200Y1576200D03*
X612499Y1615550D03*
X611900Y1577900D03*
X611999Y1603550D03*
X649399Y1644950D03*
X657099Y1668850D03*
X635099Y1691150D03*
X607599Y1716450D03*
X593399Y1668850D03*
X627299Y1659550D03*
X600599Y1645450D03*
X674999Y1676550D03*
X656499Y1697050D03*
X609499Y1692050D03*
Y1675050D03*
X642499Y1709050D03*
X665399Y1752350D03*
X650399Y1771250D03*
X593299Y1760950D03*
X619499Y1803150D03*
X627273Y1793905D03*
X606999Y1745550D03*
X625499Y1725050D03*
X675499Y1757050D03*
X675999Y1769050D03*
X675499Y1738050D03*
X642400Y1800100D03*
X659159Y1792278D03*
X626999Y1800050D03*
X645099Y1877550D03*
X667999Y1870950D03*
X632799Y1820450D03*
X627494Y1829068D03*
X608599Y1810750D03*
X669399Y1855350D03*
X627499Y1855950D03*
X611999D03*
X630699Y1872750D03*
X602799Y1887350D03*
X640999Y1815550D03*
X595199Y1820910D03*
X659549Y1815384D03*
X644049Y1810834D03*
X646799Y1926450D03*
X645399Y1906150D03*
X673899Y1966850D03*
Y1938850D03*
Y1957850D03*
X674899Y1920350D03*
Y1911350D03*
Y1892350D03*
X660299Y1964550D03*
Y1936550D03*
Y1955550D03*
X661299Y1918050D03*
Y1909050D03*
Y1890050D03*
X629699Y1947250D03*
Y1919250D03*
Y1938250D03*
X630699Y1900750D03*
Y1891750D03*
X601799Y1961850D03*
Y1933850D03*
Y1952850D03*
X602799Y1915350D03*
Y1906350D03*
X616499Y1913050D03*
Y1922050D03*
Y1894050D03*
X615499Y1959550D03*
Y1968550D03*
Y1940550D03*
X644999Y1953050D03*
X645499Y1965050D03*
X644999Y1934050D03*
X659299Y1976250D03*
X643799D03*
X622799D03*
X605299Y1975750D03*
X642499Y1987050D03*
X626999D03*
X661999Y1986550D03*
X605999Y1987050D03*
X751499Y48350D03*
X694999Y62650D03*
X757499Y63050D03*
Y44050D03*
X725499Y62050D03*
X725999Y45050D03*
X725499Y23550D03*
X680499Y6550D03*
X697999Y7050D03*
X712499Y6050D03*
X729999Y6550D03*
X749499D03*
X752099Y112150D03*
X738199Y137450D03*
X695999Y102650D03*
X694999Y81650D03*
X699699Y141750D03*
X758499Y84050D03*
X725499Y143550D03*
X725999Y124050D03*
Y106550D03*
Y77550D03*
Y92050D03*
X728899Y204550D03*
X688999Y196550D03*
X700699Y181750D03*
X699699Y160750D03*
X749499Y218550D03*
X729499D03*
X711999Y218050D03*
X677999D03*
X726499Y183550D03*
X725499Y162550D03*
X711999Y307550D03*
Y293050D03*
X723200Y275500D03*
X711499Y252550D03*
X680500Y280700D03*
X682999Y300050D03*
X683499Y263050D03*
Y248550D03*
X749899Y398550D03*
X711499Y344550D03*
X711999Y325050D03*
X683999Y340050D03*
X682999Y319050D03*
X713699Y455450D03*
X713199Y474950D03*
X712699Y434450D03*
X750399Y453550D03*
X750899Y419550D03*
X750399Y439050D03*
X694999Y480550D03*
X737999Y467050D03*
X691399Y548350D03*
X755699Y528650D03*
X756199Y509150D03*
X755199Y488150D03*
X754499Y564650D03*
X713099Y561550D03*
X713599Y542050D03*
X712599Y521050D03*
X713199Y489450D03*
X695499Y521050D03*
X695999Y501550D03*
X737999Y559050D03*
X738499Y539550D03*
Y522050D03*
Y507550D03*
X738999Y488050D03*
X691899Y588850D03*
X692399Y569350D03*
X754999Y605150D03*
X755499Y585650D03*
X717099Y636050D03*
X729699Y640350D03*
X731499Y604050D03*
Y586550D03*
Y572050D03*
X690499Y623050D03*
X744999Y626550D03*
X721499Y617550D03*
X699999Y610050D03*
X757400Y686300D03*
X720899Y712250D03*
X732499Y729250D03*
X681899Y713650D03*
X679299Y703050D03*
X727099Y715050D03*
X739399Y688150D03*
X747999Y670750D03*
X723499Y654850D03*
X693999Y648150D03*
X754999Y694050D03*
X702999Y688050D03*
Y670550D03*
Y656050D03*
X678499Y688550D03*
Y671050D03*
X749999Y700050D03*
X710899Y751150D03*
X696299Y741850D03*
X685999Y780050D03*
X694599Y763450D03*
X743099Y785350D03*
X733799Y761450D03*
X716599Y736850D03*
X723999Y802350D03*
Y783350D03*
X687099Y804650D03*
X706999Y811550D03*
Y792550D03*
X707499Y773050D03*
X728499Y841850D03*
X724999Y823350D03*
X688099Y844650D03*
X687099Y823650D03*
X729999Y881850D03*
Y862850D03*
X751599Y887350D03*
X705999Y851050D03*
Y865550D03*
X707999Y832550D03*
X751499Y855550D03*
Y836550D03*
X751999Y817050D03*
X707399Y918550D03*
Y899550D03*
X678299Y978350D03*
X730999Y902850D03*
X688099Y936350D03*
X687099Y915350D03*
Y896350D03*
X724699Y976250D03*
X723699Y955250D03*
Y936250D03*
X752599Y927350D03*
X751599Y906350D03*
X706499Y942550D03*
X749999Y965550D03*
Y946550D03*
X751399Y1023550D03*
Y1004550D03*
X752399Y1052550D03*
X734999Y1030550D03*
Y1045050D03*
X713999Y1049050D03*
Y1031550D03*
Y1017050D03*
X678299Y997350D03*
X694999Y993050D03*
X692999Y1043550D03*
Y1011550D03*
Y1026050D03*
X750999Y986550D03*
X734999Y1062550D03*
X713499Y1068550D03*
X737999Y1119050D03*
X727499Y1106050D03*
X720499Y1118550D03*
X709999Y1105550D03*
X700499Y1118550D03*
X689999Y1105550D03*
X727499Y1132650D03*
X704299D03*
X692499Y1082050D03*
Y1063050D03*
X753999Y1100050D03*
X713599Y1214650D03*
X756799Y1217650D03*
X758799Y1190150D03*
Y1199150D03*
X717999Y1169150D03*
X716999Y1148150D03*
X714399Y1199750D03*
X713399Y1178750D03*
X735999Y1220550D03*
Y1206050D03*
X737999Y1187550D03*
Y1178550D03*
Y1159550D03*
X695999Y1217550D03*
Y1203050D03*
X697999Y1184550D03*
X697499Y1172550D03*
Y1153550D03*
X684299Y1249550D03*
X740799Y1298750D03*
X723499Y1292650D03*
Y1278150D03*
X725499Y1250650D03*
Y1259650D03*
Y1231650D03*
X755399Y1300650D03*
Y1286150D03*
X757399Y1258650D03*
Y1267650D03*
Y1239650D03*
X756799Y1232150D03*
X709699Y1264550D03*
X708699Y1243550D03*
X740499Y1252550D03*
Y1270050D03*
X695999Y1235050D03*
X739199Y1348950D03*
X742099Y1320650D03*
X719199Y1322350D03*
X695999Y1323350D03*
X677999Y1347550D03*
X680299Y1365850D03*
X713899Y1386450D03*
X707899Y1346250D03*
X734199Y1373850D03*
X694999Y1388050D03*
Y1379050D03*
Y1360050D03*
X702299Y1404450D03*
X736199Y1399050D03*
X741099Y1450250D03*
X737799Y1428350D03*
X716899Y1459850D03*
X700899Y1450250D03*
X681299Y1393150D03*
X678299Y1425050D03*
X686999Y1468850D03*
X719499Y1446650D03*
X721899Y1419050D03*
X754999Y1420050D03*
Y1437550D03*
X692999Y1421050D03*
Y1406550D03*
X741099Y1498150D03*
X729199Y1492750D03*
X716199Y1503050D03*
X735799Y1533650D03*
X714599Y1533950D03*
X708899Y1549250D03*
X685299Y1551950D03*
X747199Y1509150D03*
X755499Y1507550D03*
X734499Y1563550D03*
X722199Y1564250D03*
X706700Y1579900D03*
X698599Y1568550D03*
X681299Y1579150D03*
X693599Y1602450D03*
X686699Y1638650D03*
X742000Y1560000D03*
X743400Y1578700D03*
X719999Y1605050D03*
X751300Y1604900D03*
X732999Y1620050D03*
X756299Y1679050D03*
X738799Y1677250D03*
X750099Y1694950D03*
X756499Y1712150D03*
X739199Y1716750D03*
X721199Y1723750D03*
X727399Y1694350D03*
X717099Y1702450D03*
X693099Y1722350D03*
X691999Y1660550D03*
X751899Y1752150D03*
X747799Y1766750D03*
X729499Y1778750D03*
X729999Y1756450D03*
X747499Y1734350D03*
X702599Y1730550D03*
X709099Y1751850D03*
X690499Y1744950D03*
X694599Y1768450D03*
X715999Y1763050D03*
Y1772050D03*
Y1744050D03*
X693549Y1793134D03*
X706549Y1793634D03*
X744049Y1791634D03*
X740549Y1802634D03*
X753949Y1798194D03*
X705000Y1811900D03*
X686999Y1870250D03*
X728099Y1844750D03*
X747599Y1844250D03*
X743799Y1888850D03*
X728299D03*
X753699Y1879250D03*
X732199Y1878750D03*
X744699Y1868450D03*
X758399Y1868350D03*
X723199Y1867950D03*
X743399Y1855850D03*
X725899Y1855350D03*
X690899Y1855850D03*
X706399D03*
X697999Y1844550D03*
X732999Y1868550D03*
X711500Y1817700D03*
X704300Y1828400D03*
X686473Y1818375D03*
X740549Y1810384D03*
X696299Y1898850D03*
X716599Y1918450D03*
X728799Y1933050D03*
X709199Y1962950D03*
X698299Y1948050D03*
X676399Y1901150D03*
X695299Y1926450D03*
X711899Y1944050D03*
X736799Y1919450D03*
X728799Y1908150D03*
X705599Y1891850D03*
X730499Y1954650D03*
X755299Y1902150D03*
X739799D03*
X685499Y1959050D03*
Y1968050D03*
Y1940050D03*
X755500Y1914500D03*
X721499Y1974550D03*
X696299Y1976250D03*
X678799Y1975750D03*
X754999Y1987550D03*
X737499Y1987050D03*
X717999Y1987550D03*
X702499D03*
X679499Y1987050D03*
X774399Y54050D03*
X763399Y24150D03*
X817599Y43750D03*
X824899Y25150D03*
X813299Y68350D03*
Y49350D03*
X796999Y65550D03*
X797499Y48550D03*
X796999Y27050D03*
X764999Y6550D03*
X784499Y6050D03*
X801999Y6550D03*
X818999Y6050D03*
X836499Y6550D03*
X778399Y105250D03*
X775399Y80250D03*
X821199Y137450D03*
X813299Y110850D03*
X805899Y126150D03*
X767399Y140150D03*
X796599Y123450D03*
X814299Y89350D03*
X796999Y147050D03*
X797499Y127550D03*
Y110050D03*
Y81050D03*
Y95550D03*
X837499Y138550D03*
X838499Y145050D03*
X760799Y181950D03*
X779399Y200550D03*
X786499Y219050D03*
X800999Y216550D03*
X766999Y219050D03*
X797999Y187050D03*
X796999Y166050D03*
X838999Y313550D03*
X821499Y314050D03*
X839299Y390950D03*
X819299Y394250D03*
X838499Y352050D03*
X840299Y430950D03*
X839299Y409950D03*
X820299Y434250D03*
X819299Y413250D03*
X802999Y466050D03*
X774999Y476550D03*
Y462050D03*
X825399Y540950D03*
X825899Y521450D03*
X824899Y500450D03*
X835599Y564050D03*
X834599Y543050D03*
X802999Y558050D03*
X803499Y538550D03*
Y521050D03*
Y506550D03*
X803999Y487050D03*
X775499Y553550D03*
X774499Y532550D03*
X774999Y494050D03*
X774499Y513550D03*
X835099Y583550D03*
X814499Y601550D03*
Y584050D03*
Y569550D03*
X789999Y602050D03*
Y584550D03*
Y570050D03*
X785499Y641050D03*
X777499Y638050D03*
X771800Y686600D03*
X786500Y686100D03*
X798000Y686400D03*
X764599Y655750D03*
X777499Y664550D03*
X794999D03*
X806300Y670600D03*
X841000Y671100D03*
X766499Y699050D03*
X782999Y699550D03*
X836149Y714050D03*
X766499Y705550D03*
X778999Y806950D03*
X763099Y796350D03*
X835999Y799050D03*
Y781550D03*
Y767050D03*
X811499Y799550D03*
Y782050D03*
Y767550D03*
X837799Y754150D03*
X825199Y850850D03*
X827699Y892450D03*
Y873450D03*
X776199Y879250D03*
X775199Y858250D03*
Y839250D03*
X800999Y892550D03*
X802999Y874050D03*
X801999Y853050D03*
Y834050D03*
X802499Y814550D03*
X828699Y913450D03*
X826999Y963150D03*
X773199Y960650D03*
X772199Y939650D03*
Y920650D03*
X800499Y944050D03*
Y963050D03*
X800999Y924550D03*
Y907050D03*
Y1037550D03*
Y1005550D03*
Y1020050D03*
X827999Y1003150D03*
X826999Y982150D03*
X777899Y1028050D03*
X776899Y1007050D03*
Y988050D03*
X801499Y984050D03*
X783999Y1096550D03*
X760999Y1095550D03*
X789499Y1099550D03*
X773499Y1101050D03*
X769499D03*
X773499Y1105050D03*
X769499D03*
X836149Y1118550D03*
X808299Y1175850D03*
X806599Y1189750D03*
X803599Y1211050D03*
X831499Y1209550D03*
Y1200550D03*
Y1181550D03*
X789499Y1225050D03*
X791499Y1206550D03*
X790999Y1194550D03*
Y1175550D03*
X839999Y1157550D03*
X826199Y1294450D03*
X828199Y1267850D03*
X788999Y1278150D03*
X791999Y1294450D03*
X808199Y1290350D03*
Y1275850D03*
X810199Y1248350D03*
Y1257350D03*
Y1229350D03*
X829499Y1242550D03*
Y1228050D03*
X789499Y1257050D03*
Y1239550D03*
X825500Y1379000D03*
X831499Y1324950D03*
X795299Y1326650D03*
X822199Y1335250D03*
X819199Y1353550D03*
X798299Y1344250D03*
X779399Y1361850D03*
X762499Y1335550D03*
Y1353050D03*
X799999Y1340550D03*
Y1358050D03*
X806499Y1390550D03*
X803299Y1426650D03*
X773999Y1393450D03*
X763399Y1401450D03*
X781999Y1434650D03*
X805899Y1464250D03*
X771399Y1474550D03*
X806499Y1408050D03*
X834499Y1397550D03*
X836600Y1416500D03*
X769300Y1488100D03*
X779000Y1488400D03*
X786500Y1488600D03*
X801300Y1489000D03*
X770999Y1500050D03*
X780499D03*
X839499Y1523550D03*
X773499Y1509050D03*
X769499D03*
X786999Y1506550D03*
X813300Y1604100D03*
X827199Y1622750D03*
X841499Y1638950D03*
X803599Y1618350D03*
X826499Y1609050D03*
X825999Y1578050D03*
X839899Y1562050D03*
X829200Y1719800D03*
X824100Y1719900D03*
X819400Y1721900D03*
X837199Y1660550D03*
X814599Y1642650D03*
X776999Y1647650D03*
X797299Y1646650D03*
X802899Y1670550D03*
X839199Y1683550D03*
X808899Y1698450D03*
X779999Y1717050D03*
X770399Y1699650D03*
X765099Y1664950D03*
X823499Y1693050D03*
Y1702050D03*
Y1674050D03*
X782999Y1687050D03*
X783499Y1699050D03*
X782999Y1668050D03*
X819200Y1727100D03*
X808299Y1755250D03*
X794499Y1734550D03*
X770099Y1730350D03*
X779899Y1748150D03*
X787900Y1758800D03*
X765600Y1756800D03*
X827999Y1791550D03*
X829799Y1856350D03*
X809299D03*
X791799Y1855850D03*
X801099Y1844750D03*
X785599D03*
X765099D03*
X780799Y1888850D03*
X763299Y1888350D03*
X833100Y1878500D03*
X806199Y1879250D03*
X788699Y1878750D03*
X769199Y1879250D03*
X833199Y1868450D03*
X818900Y1870800D03*
X797199Y1868450D03*
X779699Y1867950D03*
X779399Y1855850D03*
X763899D03*
X783499Y1907050D03*
X774499Y1908050D03*
X765999D03*
X838999Y1928550D03*
X790499Y1913050D03*
X775999Y1916050D03*
X840999Y1970550D03*
X768499Y1917550D03*
X813599Y1979950D03*
X789299Y1983850D03*
X829499Y1980250D03*
X829999Y1987550D03*
X812499Y1987050D03*
X792999Y1987550D03*
X777499D03*
X844799Y19850D03*
X860799Y24150D03*
X885999Y21150D03*
X855999Y6550D03*
X871499D03*
X890999Y6050D03*
X908499Y6550D03*
X923999Y6050D03*
X890700Y132500D03*
X872100Y132700D03*
X854300Y132600D03*
X891999Y146050D03*
X906999Y224150D03*
X887400Y233555D03*
X871786Y233924D03*
Y218924D03*
Y203924D03*
X907999Y264150D03*
X906999Y243150D03*
X906399Y314250D03*
Y295250D03*
X863999Y313550D03*
X887400Y259700D03*
X879878Y247724D03*
X907399Y335250D03*
X875799Y386250D03*
X904999Y385050D03*
Y370550D03*
X854499Y387550D03*
Y373050D03*
X858400Y352300D03*
X847999Y352550D03*
X870600Y346700D03*
X876799Y426250D03*
X875799Y405250D03*
X884399Y462450D03*
Y443450D03*
X905499Y462050D03*
X904499Y441050D03*
Y422050D03*
X904999Y402550D03*
X854999Y464550D03*
X853999Y443550D03*
X854499Y405050D03*
X853999Y424550D03*
X861199Y546050D03*
X860199Y525050D03*
X885399Y483450D03*
X914699Y524650D03*
X913699Y503650D03*
Y484650D03*
X860699Y565550D03*
X898999Y622050D03*
Y604550D03*
X860499Y607550D03*
X861800Y591200D03*
X918999Y641550D03*
X870719Y609705D03*
X894000Y642400D03*
X870719Y639705D03*
X870773Y624705D03*
X895999Y720050D03*
Y702550D03*
X900999Y670050D03*
Y652550D03*
X918499Y712050D03*
X918999Y673550D03*
X918499Y693050D03*
X918999Y656050D03*
X887401Y665000D03*
X881200Y652100D03*
X859999Y713050D03*
X871385Y719436D03*
X871786Y709482D03*
X871499Y689436D03*
X871786Y679436D03*
X860796Y678632D03*
X921399Y796350D03*
X921899Y776850D03*
Y759350D03*
Y744850D03*
X884499Y799050D03*
Y781550D03*
Y767050D03*
X859999Y799550D03*
Y782050D03*
Y767550D03*
X919499Y733050D03*
X856299Y753150D03*
X846799Y754150D03*
X865000Y752100D03*
X889699Y876050D03*
X847799Y828250D03*
X857099Y873450D03*
X920399Y886850D03*
Y869350D03*
Y854850D03*
X922399Y836350D03*
X921399Y815350D03*
X898499Y862050D03*
Y844550D03*
Y830050D03*
X873999Y862550D03*
Y845050D03*
Y830550D03*
X886999Y947250D03*
Y907350D03*
X867199Y941350D03*
X866199Y920350D03*
Y901350D03*
X850999Y962550D03*
Y943550D03*
X919899Y925350D03*
X920899Y946350D03*
X919899Y906350D03*
X851999Y983550D03*
X921499Y1031050D03*
X920999Y1050550D03*
X921499Y1013550D03*
Y999050D03*
X870468Y1030227D03*
X880033Y1058592D03*
X886919Y1044478D03*
X870298Y1045227D03*
X870777Y1014948D03*
X921999Y1090550D03*
X920999Y1069550D03*
X887400Y1070600D03*
X859999Y1118550D03*
X841999D03*
X845799Y1190450D03*
X849799Y1199750D03*
X846499Y1170450D03*
X897299Y1182450D03*
X887999Y1209350D03*
X871399Y1201850D03*
Y1210850D03*
Y1182850D03*
X892499Y1224550D03*
X851999Y1218550D03*
X856400Y1157700D03*
X848999Y1158050D03*
X863300Y1153800D03*
X872099Y1268150D03*
X871399Y1291450D03*
X860099Y1295450D03*
X869399Y1243850D03*
Y1229350D03*
X890499Y1285550D03*
Y1271050D03*
X892499Y1252550D03*
Y1243550D03*
X850499Y1300050D03*
Y1282550D03*
Y1268050D03*
X852499Y1249550D03*
X851999Y1237550D03*
X875399Y1322650D03*
X868499Y1392550D03*
X890999Y1336550D03*
Y1354050D03*
X841999Y1341050D03*
Y1358550D03*
X894499Y1423550D03*
Y1441050D03*
X868499Y1410050D03*
X886913Y1449010D03*
X879727Y1463696D03*
X871836Y1450460D03*
Y1435460D03*
Y1420460D03*
X914599Y1521650D03*
X910899Y1549250D03*
X894499Y1522050D03*
Y1539550D03*
X895499Y1488050D03*
X902759Y1509585D03*
X861999Y1522550D03*
X843999Y1523550D03*
X887499Y1476050D03*
X865300Y1557700D03*
X923599Y1634350D03*
X909700Y1576400D03*
X907500Y1604000D03*
X908899Y1630050D03*
X868099Y1635650D03*
X887299Y1620050D03*
X886900Y1604100D03*
X873099Y1572550D03*
X850099Y1572250D03*
X849900Y1605100D03*
X852499Y1621350D03*
X866499Y1603050D03*
Y1612050D03*
X864000Y1578200D03*
X858400Y1561900D03*
X850499Y1562050D03*
X879200Y1698700D03*
X879900Y1709300D03*
X883900Y1709500D03*
X855350Y1703201D03*
X914899Y1657550D03*
X922599Y1682150D03*
X903599Y1686850D03*
X895999Y1661250D03*
X877699Y1646650D03*
X855799Y1658250D03*
X882999Y1678250D03*
X864099Y1683550D03*
X842799Y1701150D03*
X875900Y1709500D03*
X902900Y1709800D03*
X842500Y1799000D03*
X892700Y1727800D03*
X879399Y1798150D03*
X911299Y1800850D03*
X864000Y1748000D03*
X866699Y1770950D03*
X853799Y1790850D03*
X844499Y1788050D03*
X892700Y1736500D03*
X863099Y1813150D03*
X903299Y1814750D03*
X894999Y1829050D03*
X922899Y1853650D03*
X905299Y1852650D03*
X900299Y1876950D03*
X842199Y1879250D03*
X914999Y1887050D03*
Y1868050D03*
X862499Y1823550D03*
X854977Y1818994D03*
X887401Y1881500D03*
X894000Y1868452D03*
X887499Y1855550D03*
X869999Y1855972D03*
X871836Y1840972D03*
X869634Y1826876D03*
X914899Y1912450D03*
X916599Y1942650D03*
X897599Y1938750D03*
X914899Y1972250D03*
X873399Y1963650D03*
X904299Y1954950D03*
X897299Y1904150D03*
X907599Y1930050D03*
X915499Y1899050D03*
X861414Y1928550D03*
X843999D03*
X856999Y1970050D03*
X849999Y1970550D03*
X865200Y1968000D03*
X879399Y1974550D03*
X850499Y1977950D03*
X868699Y1983250D03*
X921499Y1986550D03*
X901999Y1987050D03*
X864999D03*
X849499D03*
X884499Y1986550D03*
X974699Y64650D03*
X977399Y44050D03*
X954799Y17850D03*
X974699Y21450D03*
X991399Y22450D03*
X1002699Y40050D03*
X991999Y56050D03*
X941499Y6550D03*
X960999D03*
X976499D03*
X995999Y6050D03*
X967499Y47050D03*
Y56050D03*
Y64050D03*
X983099Y83650D03*
X1005299Y71350D03*
X977699Y109150D03*
X994399Y101250D03*
X981099Y123450D03*
X939199Y142050D03*
X968399Y137150D03*
X967999Y73050D03*
Y82050D03*
X988699Y174350D03*
X967399Y180350D03*
X956099Y181350D03*
X958799Y167350D03*
X1004799Y231450D03*
X1005299Y211950D03*
Y194450D03*
Y179950D03*
X952799Y231150D03*
Y213650D03*
Y199150D03*
X982999Y203550D03*
Y221050D03*
Y189050D03*
X932499Y223550D03*
Y206050D03*
Y191550D03*
X1005299Y305450D03*
Y290950D03*
X1005799Y271450D03*
X1004799Y250450D03*
X952799Y310150D03*
X953299Y290650D03*
X952299Y269650D03*
Y250650D03*
X983999Y316050D03*
Y301550D03*
X933499Y304050D03*
X983499Y280550D03*
X982499Y259550D03*
Y240550D03*
X932999Y283050D03*
X931999Y262050D03*
Y243050D03*
X1005799Y382450D03*
X1004799Y361450D03*
X1005299Y322950D03*
X1004799Y342450D03*
X952299Y380650D03*
X952799Y342150D03*
X952299Y361650D03*
X952799Y324650D03*
X984499Y393050D03*
X983499Y372050D03*
Y353050D03*
X983999Y333550D03*
X933999Y395550D03*
X932999Y374550D03*
X933499Y336050D03*
X932999Y355550D03*
X933499Y318550D03*
X966199Y473350D03*
X1000699Y482350D03*
Y463350D03*
X954799Y451650D03*
Y434150D03*
Y419650D03*
X953299Y401650D03*
X983499Y464050D03*
X983999Y427050D03*
Y444550D03*
Y412550D03*
X933499Y447050D03*
X932999Y466550D03*
X933499Y429550D03*
Y415050D03*
X967199Y513350D03*
X966199Y492350D03*
X1001699Y503350D03*
X1003499Y546350D03*
X1003999Y526850D03*
X951299Y560150D03*
Y541150D03*
X951799Y521650D03*
Y504150D03*
Y489650D03*
X985999Y536550D03*
Y554050D03*
Y522050D03*
X935499Y556550D03*
Y539050D03*
Y524550D03*
X984499Y504050D03*
X983499Y483050D03*
X933999Y506550D03*
X932999Y485550D03*
X967799Y606350D03*
X966799Y585350D03*
Y566350D03*
X1005999Y636350D03*
Y618850D03*
X1004499Y586350D03*
X1005999Y604350D03*
X1003499Y565350D03*
X950299Y631650D03*
Y614150D03*
Y599650D03*
X952299Y581150D03*
X969499Y639050D03*
X986499Y613550D03*
X985499Y592550D03*
Y573550D03*
X935999Y616050D03*
X934999Y595050D03*
Y576050D03*
X949799Y670150D03*
X950799Y691150D03*
X949799Y651150D03*
X969999Y730550D03*
X968999Y709550D03*
Y690550D03*
X969499Y653550D03*
Y671050D03*
Y795750D03*
X969999Y776250D03*
Y758750D03*
Y744250D03*
X994499Y803550D03*
Y784550D03*
X994999Y747550D03*
Y765050D03*
Y733050D03*
X943999Y806050D03*
X944499Y767550D03*
X943999Y787050D03*
X944499Y750050D03*
Y735550D03*
X970499Y879750D03*
Y862250D03*
Y847750D03*
Y835750D03*
X969499Y814750D03*
X992999Y894550D03*
X993499Y857550D03*
Y875050D03*
Y843050D03*
X942999Y877550D03*
Y860050D03*
Y845550D03*
X995499Y824550D03*
X944999Y827050D03*
X994499Y973550D03*
Y956050D03*
Y941550D03*
X949299Y977450D03*
X970999Y939250D03*
X969999Y918250D03*
Y899250D03*
X993999Y934550D03*
X992999Y913550D03*
X943499Y937050D03*
X942499Y916050D03*
Y897050D03*
X994999Y1033050D03*
Y1045050D03*
X993999Y1012050D03*
Y993050D03*
X948799Y1047950D03*
Y1028950D03*
X949299Y1009450D03*
Y991950D03*
X971499Y1048050D03*
X971999Y1011050D03*
Y1028550D03*
Y996550D03*
X949799Y1068950D03*
Y1080950D03*
X998599Y1128450D03*
Y1110950D03*
Y1096450D03*
X950699Y1139750D03*
Y1122250D03*
Y1107750D03*
X975999Y1115550D03*
Y1133050D03*
Y1101050D03*
X925499Y1135550D03*
Y1118050D03*
Y1103550D03*
X972499Y1088050D03*
X971499Y1067050D03*
X999099Y1214450D03*
Y1199950D03*
Y1187950D03*
X998099Y1147950D03*
Y1166950D03*
X951199Y1225750D03*
Y1211250D03*
Y1199250D03*
X950199Y1159250D03*
Y1178250D03*
X976499Y1219050D03*
Y1204550D03*
X925999Y1221550D03*
Y1207050D03*
X976499Y1192550D03*
X975499Y1171550D03*
Y1152550D03*
X925999Y1195050D03*
X924999Y1174050D03*
Y1155050D03*
X999599Y1291450D03*
X998599Y1270450D03*
Y1251450D03*
X999099Y1231950D03*
X951699Y1302750D03*
X950699Y1281750D03*
Y1262750D03*
X951199Y1243250D03*
X976999Y1296050D03*
X975999Y1275050D03*
Y1256050D03*
X976499Y1236550D03*
X926499Y1298550D03*
X925499Y1277550D03*
X925999Y1239050D03*
X925499Y1258550D03*
X975100Y1342600D03*
X1000700Y1358100D03*
X996500Y1324800D03*
X952499Y1361850D03*
X944000Y1391900D03*
X943799Y1380850D03*
Y1342950D03*
X965099Y1324350D03*
X928499Y1325350D03*
X976499Y1377050D03*
Y1362550D03*
X925999Y1379550D03*
Y1365050D03*
X992500Y1397300D03*
X964400Y1409700D03*
X946700Y1426500D03*
X994200Y1421500D03*
X924999Y1471050D03*
X926499Y1456550D03*
X925499Y1435550D03*
X925999Y1397050D03*
X925499Y1416550D03*
X973200Y1516400D03*
X972500Y1529100D03*
X966600D03*
X961400Y1528700D03*
X961900Y1522400D03*
X967100Y1522800D03*
X973000D03*
X962100Y1516000D03*
X967300Y1516400D03*
X972700Y1534800D03*
X972000Y1547500D03*
X966100D03*
X960900Y1547100D03*
X961400Y1540800D03*
X966600Y1541200D03*
X972500D03*
X961600Y1534400D03*
X966800Y1534800D03*
X972700Y1553300D03*
X961600Y1552900D03*
X966800Y1553300D03*
X944000Y1511300D03*
X943199Y1531650D03*
X924499Y1541550D03*
X924999Y1503050D03*
X924499Y1522550D03*
X924999Y1485550D03*
X972000Y1566000D03*
X966100D03*
X960900Y1565600D03*
X961400Y1559300D03*
X966600Y1559700D03*
X972500D03*
X973000Y1572800D03*
X972300Y1585500D03*
X966400D03*
X961200Y1585100D03*
X961700Y1578800D03*
X966900Y1579200D03*
X972800D03*
X961900Y1572400D03*
X967100Y1572800D03*
X972400Y1592000D03*
X966500D03*
X961300Y1591600D03*
X972200Y1598400D03*
X966300D03*
X961100Y1598000D03*
X960600Y1604300D03*
X971700Y1604700D03*
X965800D03*
X944499Y1632650D03*
X925599Y1612050D03*
X933199Y1577550D03*
X925499Y1562550D03*
X989999Y1718050D03*
X958799Y1715750D03*
X957799Y1646950D03*
X955499Y1690850D03*
X941499Y1679550D03*
X940499Y1656950D03*
X931499Y1702050D03*
X941800Y1787700D03*
X934200Y1793500D03*
X993299Y1734350D03*
X994999Y1748950D03*
X976600Y1757100D03*
X965349Y1742000D03*
X949799Y1756250D03*
X976399Y1772250D03*
X954499Y1783550D03*
X941499Y1776250D03*
X932199Y1801850D03*
X971000Y1803000D03*
X999999Y1775250D03*
X976399Y1791150D03*
X993499Y1805550D03*
X928000Y1818500D03*
X1003599Y1846650D03*
X995699Y1858950D03*
X971500Y1871500D03*
X937199Y1869950D03*
X993499Y1824550D03*
Y1833550D03*
X987999Y1971950D03*
Y1949050D03*
X1000999Y1946350D03*
X991999Y1915750D03*
X966799Y1892150D03*
X974699Y1914450D03*
X945199Y1946350D03*
X955799Y1951950D03*
X954099Y1915450D03*
X938199Y1917150D03*
X1002500Y1953500D03*
X1001599Y1921450D03*
X992299Y1929050D03*
X989999Y1962650D03*
X980999Y1933350D03*
X947499Y1936050D03*
X946199Y1966650D03*
X937499Y1893850D03*
X971499Y1956050D03*
Y1965050D03*
Y1937050D03*
X930999Y1950050D03*
X931499Y1962050D03*
X930999Y1931050D03*
X955499Y1893050D03*
Y1902050D03*
X953799Y1977950D03*
X930199Y1979550D03*
X1005000Y1980500D03*
X994999Y1986550D03*
X973999D03*
X956499Y1986050D03*
X936999Y1986550D03*
X1022000Y15500D03*
X1013499Y6550D03*
X1020499Y50550D03*
X1020999Y33050D03*
X1010599Y115550D03*
X1020499Y122550D03*
X1020999Y105050D03*
Y85550D03*
Y70050D03*
X1021499Y141050D03*
X1020999Y230550D03*
X1021499Y213050D03*
Y193550D03*
Y178050D03*
X1020999Y158550D03*
Y304550D03*
Y289050D03*
X1020499Y269550D03*
X1020999Y252050D03*
X1020499Y341550D03*
X1020999Y324050D03*
X1020499Y391550D03*
X1020999Y374050D03*
X1007299Y432450D03*
Y414950D03*
Y400450D03*
X1020499Y463550D03*
X1020999Y446050D03*
Y426550D03*
Y411050D03*
X1021999Y558550D03*
Y539050D03*
Y523550D03*
X1021499Y504050D03*
X1021999Y486550D03*
X1021499Y576050D03*
X1020999Y642550D03*
X1020499Y623050D03*
X1020999Y605550D03*
X1020499Y695050D03*
X1020999Y677550D03*
Y658050D03*
Y720050D03*
X1020499Y809550D03*
X1020999Y792050D03*
Y772550D03*
Y757050D03*
X1020499Y737550D03*
Y880550D03*
Y865050D03*
X1019999Y845550D03*
X1020499Y828050D03*
X1019999Y917550D03*
X1020499Y900050D03*
X1019999Y971050D03*
X1019499Y951550D03*
X1019999Y934050D03*
Y986550D03*
Y1058550D03*
Y1043050D03*
X1019499Y1023550D03*
X1019999Y1006050D03*
X1020499Y1134050D03*
Y1118550D03*
X1019999Y1099050D03*
X1020499Y1081550D03*
X1019499Y1198550D03*
Y1183050D03*
X1018999Y1163550D03*
X1019499Y1146050D03*
X1016999Y1219050D03*
X1016499Y1301050D03*
Y1236550D03*
X1016999Y1256050D03*
Y1271550D03*
X1023300Y1344400D03*
X1024300Y1365200D03*
X1022599Y1322950D03*
X1024300Y1393600D03*
X1008599Y1716050D03*
X1022299Y1715750D03*
X1008999Y1702450D03*
X1016899Y1731650D03*
X1026899Y1768550D03*
X1020299Y1746650D03*
X1015299Y1765950D03*
X1009999Y1797450D03*
X1022499Y1802050D03*
X1022999Y1784550D03*
X1011299Y1860650D03*
X1007599Y1818450D03*
X1022999Y1821550D03*
Y1837050D03*
X1020499Y1877550D03*
X1020999Y1860050D03*
Y1912550D03*
Y1897050D03*
X1017499Y1954550D03*
X1017999Y1937050D03*
Y1987050D03*
X1023000Y1973000D03*
G54D20*
G01X26662Y861550D02*
X34670Y869558D01*
Y1002085D01*
X31711Y1005044D01*
Y1014811D01*
X37338Y1020438D01*
Y1023127D01*
X39374Y1025319D01*
Y1027617D01*
X39375Y1027618D01*
Y1036971D01*
X36334Y1040012D01*
Y1060618D01*
X36335Y1060619D01*
Y1431910D01*
X35804Y1432441D01*
X35803Y1432619D01*
X35788Y1432693D01*
Y1438579D01*
X28711Y1445656D01*
X27946D01*
X25600Y1448002D01*
Y1457418D01*
X25438Y1457580D01*
Y1459878D01*
X25446Y1459968D01*
X25495Y1460561D01*
X25512Y1460768D01*
Y1460771D01*
X25513Y1460773D01*
X25592Y1461046D01*
Y1486993D01*
X27248Y1488649D01*
Y1490400D01*
X29500Y1492652D01*
Y1494700D01*
X27018Y1497182D01*
Y1520896D01*
X26102Y1521812D01*
X23417D01*
X20825Y1524404D01*
Y1524428D01*
X20626Y1524726D01*
X20484Y1525069D01*
X20411Y1525434D01*
Y1681700D01*
X3318Y1698793D01*
Y1781202D01*
X26872Y1804756D01*
X26910Y1804948D01*
Y1814754D01*
X26872Y1814946D01*
X22436Y1819382D01*
Y1831021D01*
X31299Y1839884D01*
X47166D01*
G01X358999Y61550D02*
Y63136D01*
X324400Y97735D01*
Y100600D01*
X264200Y160800D01*
X233200D01*
X230300Y163700D01*
X228000D01*
X225400Y161100D01*
X150820D01*
X146560Y165360D01*
X130042Y181880D01*
X95872Y216050D01*
X65999D01*
G01X28100Y374000D02*
X39500Y385400D01*
Y430700D01*
X61400Y452600D01*
G01X28900Y417800D02*
X37500Y426400D01*
Y435100D01*
X57900Y455500D01*
X65000D01*
G01X98700Y842600D02*
X101450Y839850D01*
Y648750D01*
X53374Y600674D01*
Y591426D01*
X56000Y588800D01*
Y558500D01*
X68000Y546500D01*
G01X72500Y545000D02*
X71700Y544200D01*
X66500D01*
X54225Y556475D01*
Y588064D01*
X51599Y590690D01*
Y601410D01*
X99675Y649486D01*
Y818933D01*
X98700Y819908D01*
Y822550D01*
G01X98000Y833500D02*
X95575Y831075D01*
Y647897D01*
X49824Y602146D01*
Y589954D01*
X52450Y587328D01*
Y553350D01*
X38700Y539600D01*
X27199D01*
G01X42202Y608195D02*
Y609544D01*
X93200Y660542D01*
Y837300D01*
X80000Y850500D01*
X76978D01*
X76540Y850938D01*
G01X41400Y611500D02*
X87900Y658000D01*
Y814700D01*
X86700Y815900D01*
Y840800D01*
X79500Y848000D01*
X75800D01*
X75500Y847700D01*
G01X38208Y1569841D02*
X38228Y1569821D01*
Y1558027D01*
X37086Y1556885D01*
Y1542207D01*
X41437Y1537856D01*
Y1474660D01*
X43475Y1472622D01*
Y1446334D01*
X41660Y1444519D01*
Y1058411D01*
X41659Y1058410D01*
Y1042220D01*
X44700Y1039179D01*
Y1025410D01*
X44699Y1025409D01*
Y1023219D01*
X42663Y1021032D01*
Y1016412D01*
X40447Y1014196D01*
Y862869D01*
X34347Y856769D01*
Y835947D01*
X32436Y834036D01*
Y819010D01*
X33587Y817859D01*
Y813038D01*
X28750Y808201D01*
Y785550D01*
X30787Y783513D01*
Y746269D01*
X29474Y744956D01*
Y703650D01*
X31887Y701237D01*
Y693466D01*
X21611Y683190D01*
Y664515D01*
X26226Y659900D01*
X30019D01*
X40500Y649419D01*
Y643800D01*
X41500Y642800D01*
G01X47101Y632355D02*
X59944Y645198D01*
Y814848D01*
X57948Y816844D01*
Y831085D01*
X62362Y835499D01*
Y839557D01*
X61611Y840308D01*
Y843832D01*
X61747Y843968D01*
Y1005247D01*
X64200Y1007700D01*
Y1012581D01*
X72787Y1021168D01*
Y1049309D01*
X62962Y1059134D01*
Y1229419D01*
X62969Y1229635D01*
X63052Y1229997D01*
X63200Y1230325D01*
Y1231774D01*
X62960Y1232014D01*
Y1235152D01*
X63200Y1235392D01*
Y1243027D01*
X62962Y1243266D01*
Y1391759D01*
X63200Y1391997D01*
Y1392000D01*
X74836Y1403636D01*
Y1409153D01*
X64262Y1419727D01*
Y1435567D01*
X64775Y1436080D01*
Y1481454D01*
X63066Y1483163D01*
X62975Y1483619D01*
Y1553578D01*
X60687Y1555866D01*
Y1563085D01*
X60097Y1563675D01*
Y1635367D01*
X59410Y1636054D01*
Y1740239D01*
X43559Y1756090D01*
Y1767884D01*
G01X80500Y817000D02*
X83900Y813600D01*
Y656600D01*
X44100Y616800D01*
X32100D01*
X26800Y611500D01*
G01X39000Y1573500D02*
X40096Y1572404D01*
Y1557384D01*
X38861Y1556149D01*
Y1542943D01*
X43212Y1538592D01*
Y1475396D01*
X45250Y1473358D01*
Y1445598D01*
X43435Y1443783D01*
Y1057675D01*
X43434Y1057674D01*
Y1042956D01*
X46475Y1039915D01*
Y1024674D01*
X46474Y1024673D01*
Y1022516D01*
X44438Y1020332D01*
Y1015676D01*
X42222Y1013460D01*
Y862133D01*
X36122Y856033D01*
Y835211D01*
X34211Y833300D01*
Y819746D01*
X35362Y818595D01*
Y812302D01*
X30525Y807465D01*
Y786575D01*
X32562Y784538D01*
Y745533D01*
X31249Y744220D01*
Y705109D01*
X33662Y702696D01*
Y692488D01*
X25812Y684638D01*
Y678412D01*
X46788Y657436D01*
Y640288D01*
X41500Y635000D01*
G01X37216Y807951D02*
Y804884D01*
X34688Y802356D01*
Y802268D01*
X33582Y801162D01*
X33494D01*
X32300Y799968D01*
Y788717D01*
X34376Y786641D01*
Y744836D01*
X33024Y743484D01*
Y706376D01*
X36824Y702576D01*
Y689997D01*
X29527Y682700D01*
X27700D01*
G01X44046Y799554D02*
X46017Y801525D01*
X47669D01*
X48775Y802631D01*
Y806114D01*
X44688Y810201D01*
Y833733D01*
X46383Y835428D01*
Y856250D01*
X49322Y859189D01*
Y1010516D01*
X51538Y1012732D01*
Y1017494D01*
X53574Y1019531D01*
Y1021729D01*
X53575Y1021730D01*
Y1042859D01*
X50534Y1045900D01*
Y1054730D01*
X50535Y1054731D01*
Y1440839D01*
X52350Y1442654D01*
Y1476302D01*
X50312Y1478340D01*
Y1548664D01*
X48076Y1550900D01*
Y1558113D01*
X47672Y1558516D01*
Y1630215D01*
X46985Y1630902D01*
Y1711015D01*
X29078Y1728922D01*
Y1786042D01*
X30274Y1787238D01*
G01X36300Y1805123D02*
Y1804140D01*
X25528Y1793368D01*
Y1727450D01*
X43435Y1709543D01*
Y1629430D01*
X44087Y1628778D01*
Y1558989D01*
X44122Y1558954D01*
Y1556388D01*
X42411Y1554677D01*
Y1544415D01*
X46762Y1540064D01*
Y1476868D01*
X48800Y1474830D01*
Y1444126D01*
X46985Y1442311D01*
Y1056203D01*
X46984Y1056202D01*
Y1044428D01*
X50025Y1041387D01*
Y1023202D01*
X50024Y1023201D01*
Y1021002D01*
X48488Y1019466D01*
X47988Y1018931D01*
Y1014204D01*
X45772Y1011988D01*
Y860661D01*
X42833Y857722D01*
Y836900D01*
X37761Y831828D01*
Y821218D01*
X39104Y819875D01*
Y800721D01*
X37416Y799033D01*
G01X29899Y1821050D02*
X32197Y1818752D01*
X32235Y1818560D01*
Y1802732D01*
X32199Y1802550D01*
X23753Y1794104D01*
Y1726655D01*
X41340Y1709068D01*
Y1604161D01*
X40311Y1603132D01*
Y1574859D01*
X41871Y1573299D01*
Y1556648D01*
X40636Y1555413D01*
Y1543679D01*
X44987Y1539328D01*
Y1476132D01*
X47025Y1474094D01*
Y1444862D01*
X45210Y1443047D01*
Y1056939D01*
X45209Y1056938D01*
Y1043692D01*
X48250Y1040651D01*
Y1023938D01*
X48249Y1023937D01*
Y1021814D01*
X46213Y1019632D01*
Y1014940D01*
X43997Y1012724D01*
Y861397D01*
X37897Y855297D01*
Y834475D01*
X35986Y832564D01*
Y820482D01*
X37137Y819331D01*
Y811566D01*
X37099Y811528D01*
Y811350D01*
G01X35675Y1783450D02*
X34403Y1782178D01*
Y1731130D01*
X52310Y1713223D01*
Y1633110D01*
X52997Y1632423D01*
Y1560726D01*
X53401Y1560322D01*
Y1553108D01*
X55637Y1550872D01*
Y1480548D01*
X57675Y1478510D01*
Y1440446D01*
X55860Y1438631D01*
Y1052523D01*
X55859Y1052522D01*
Y1048108D01*
X58900Y1045067D01*
Y1017325D01*
X56863Y1015288D01*
Y1010524D01*
X54647Y1008308D01*
Y855647D01*
X54511Y855511D01*
Y835181D01*
X48875Y829545D01*
Y819605D01*
X48012Y818742D01*
Y809388D01*
X51100Y806300D01*
G01X39000Y1750800D02*
X39629Y1750171D01*
X40799D01*
X54085Y1736885D01*
Y1633846D01*
X54772Y1633159D01*
Y1561464D01*
X55176Y1561061D01*
Y1553844D01*
X57412Y1551608D01*
Y1481284D01*
X59450Y1479246D01*
Y1439710D01*
X57635Y1437895D01*
Y1051787D01*
X57634Y1051786D01*
Y1048844D01*
X61100Y1045378D01*
Y1017014D01*
X58875Y1014789D01*
Y1010025D01*
X56422Y1007572D01*
Y854911D01*
X56286Y854775D01*
Y834445D01*
X52186Y830345D01*
Y814968D01*
X56281Y810873D01*
Y801350D01*
G01X42275Y1754000D02*
X57635Y1738640D01*
Y1635318D01*
X58322Y1634631D01*
Y1562939D01*
X58912Y1562349D01*
Y1555130D01*
X61185Y1552857D01*
Y1482533D01*
X63000Y1480718D01*
Y1436816D01*
X61185Y1435001D01*
Y1058400D01*
X70739Y1048846D01*
Y1021631D01*
X62425Y1013317D01*
Y1008553D01*
X59972Y1006100D01*
Y853439D01*
X59836Y853303D01*
Y839572D01*
X60587Y838821D01*
Y836235D01*
X56173Y831821D01*
Y814027D01*
X58169Y812031D01*
Y800568D01*
X46976Y789375D01*
X35300D01*
G01X35559Y795112D02*
X36165D01*
X42913Y801860D01*
Y834469D01*
X44608Y836164D01*
Y856986D01*
X47547Y859925D01*
Y1011252D01*
X49763Y1013468D01*
Y1018229D01*
X49778Y1018245D01*
X51799Y1020266D01*
Y1022465D01*
X51800Y1022466D01*
Y1042123D01*
X48759Y1045164D01*
Y1055466D01*
X48760Y1055467D01*
Y1441575D01*
X50575Y1443390D01*
Y1475566D01*
X48537Y1477604D01*
Y1540800D01*
X44812Y1544525D01*
Y1547575D01*
X46187Y1548950D01*
Y1557490D01*
X45897Y1557779D01*
Y1629479D01*
X45210Y1630166D01*
Y1710279D01*
X27303Y1728186D01*
Y1791954D01*
X32099Y1796750D01*
Y1797150D01*
G01X49300Y836500D02*
X50835Y838035D01*
Y857357D01*
X51097Y857619D01*
Y1009780D01*
X53313Y1011996D01*
Y1016759D01*
X55349Y1018796D01*
Y1020993D01*
X55350Y1020994D01*
Y1043595D01*
X52309Y1046636D01*
Y1053994D01*
X52310Y1053995D01*
Y1440103D01*
X54125Y1441918D01*
Y1477038D01*
X52087Y1479076D01*
Y1549400D01*
X49851Y1551636D01*
Y1558850D01*
X49447Y1559253D01*
Y1630951D01*
X48760Y1631638D01*
Y1711751D01*
X30853Y1729658D01*
Y1783838D01*
X34099Y1787084D01*
Y1799428D01*
X38188Y1803517D01*
Y1815776D01*
X32000Y1821964D01*
Y1824703D01*
X28550Y1828153D01*
G01X38878Y1799571D02*
X40741Y1797708D01*
X41260D01*
X42366Y1796602D01*
Y1795038D01*
X41260Y1793932D01*
X41211D01*
X39587Y1792308D01*
Y1789068D01*
X38481Y1787962D01*
X37517D01*
X32628Y1783073D01*
Y1730394D01*
X50535Y1712487D01*
Y1632374D01*
X51222Y1631687D01*
Y1559990D01*
X51626Y1559586D01*
Y1552372D01*
X53862Y1550136D01*
Y1479812D01*
X55900Y1477774D01*
Y1441182D01*
X54085Y1439367D01*
Y1053259D01*
X54084Y1053258D01*
Y1047372D01*
X57125Y1044331D01*
Y1018062D01*
X55088Y1016024D01*
Y1011260D01*
X52872Y1009044D01*
Y856883D01*
X52610Y856621D01*
Y836165D01*
X47100Y830655D01*
Y820500D01*
X46700Y820100D01*
G01X48049Y1791450D02*
X41212Y1784613D01*
Y1779841D01*
X39896Y1778525D01*
Y1753709D01*
X55860Y1737745D01*
Y1634582D01*
X56547Y1633895D01*
Y1562201D01*
X56951Y1561798D01*
Y1554580D01*
X59187Y1552344D01*
Y1482020D01*
X61225Y1479982D01*
Y1437552D01*
X59410Y1435737D01*
Y1057664D01*
X68964Y1048110D01*
Y1022367D01*
X60650Y1014053D01*
Y1009289D01*
X58197Y1006836D01*
Y854175D01*
X58061Y854039D01*
Y837888D01*
X58699Y837250D01*
G01X68860Y838706D02*
Y839488D01*
X67787Y840561D01*
X66924Y841425D01*
Y988041D01*
X77036Y998154D01*
Y1005968D01*
X79012Y1007944D01*
Y1012226D01*
X79568Y1012782D01*
Y1023066D01*
X76337Y1026297D01*
Y1190103D01*
X80662Y1194428D01*
Y1235460D01*
X70545Y1245577D01*
Y1375434D01*
X85063Y1389952D01*
Y1406459D01*
X70100Y1421422D01*
Y1483662D01*
X68943Y1484819D01*
Y1555143D01*
X66012Y1558074D01*
Y1565305D01*
X65649Y1565668D01*
Y1628002D01*
X83100Y1645453D01*
Y1649457D01*
X83288Y1650401D01*
Y1651411D01*
X83100Y1652355D01*
Y1656406D01*
X65297Y1674209D01*
Y1743534D01*
X47440Y1761391D01*
G01X47604Y1769005D02*
X67072Y1749537D01*
Y1674945D01*
X84875Y1657142D01*
Y1652531D01*
X85063Y1651587D01*
Y1650225D01*
X84875Y1649281D01*
Y1644717D01*
X67424Y1627266D01*
Y1566404D01*
X67787Y1566041D01*
Y1558810D01*
X70718Y1555879D01*
Y1485555D01*
X71875Y1484398D01*
Y1422158D01*
X86838Y1407195D01*
Y1389216D01*
X72320Y1374698D01*
Y1259813D01*
X83288Y1248845D01*
Y1194543D01*
X81191Y1192446D01*
X81100Y1192354D01*
Y1192178D01*
X80603Y1191681D01*
X80562Y1191581D01*
X79966Y1190691D01*
X78112Y1188837D01*
Y1027033D01*
X81343Y1023802D01*
Y1013518D01*
X81344Y1013517D01*
Y1012047D01*
X80787Y1011490D01*
Y1007087D01*
X80038Y1006338D01*
X79917D01*
X78811Y1005232D01*
Y997415D01*
X68699Y987303D01*
Y843750D01*
X69499Y842950D01*
G01X63499Y843050D02*
Y842565D01*
X64137Y841927D01*
Y834763D01*
X59723Y830349D01*
Y824178D01*
X62405Y821496D01*
Y820300D01*
G01X63499Y843050D02*
X63522Y843073D01*
Y987373D01*
X74836Y998688D01*
Y1006000D01*
X69700Y1011136D01*
Y1015570D01*
X74562Y1020432D01*
Y1190839D01*
X74724Y1191001D01*
Y1191002D01*
X78887Y1195165D01*
Y1234724D01*
X68770Y1244841D01*
Y1376170D01*
X83288Y1390688D01*
Y1405723D01*
X67812Y1421199D01*
Y1434095D01*
X68325Y1434608D01*
Y1482926D01*
X67168Y1484083D01*
Y1554407D01*
X64237Y1557338D01*
Y1564569D01*
X63874Y1564932D01*
Y1636612D01*
X62960Y1637526D01*
Y1743183D01*
X45512Y1760631D01*
Y1771607D01*
X45782Y1771877D01*
G01X26099Y1824950D02*
Y1820741D01*
X30422Y1816418D01*
X30460Y1816226D01*
Y1803472D01*
X30423Y1803285D01*
X21978Y1794840D01*
Y1725919D01*
X39565Y1708332D01*
Y1604897D01*
X38262Y1603594D01*
Y1590238D01*
X36320Y1588296D01*
Y1561899D01*
X33008Y1558587D01*
Y1554948D01*
X35310Y1552646D01*
Y1539513D01*
X36023Y1538800D01*
Y1528026D01*
X39662Y1524387D01*
Y1473924D01*
X41700Y1471886D01*
Y1447070D01*
X39885Y1445255D01*
Y1059147D01*
X39884Y1059146D01*
Y1041484D01*
X42925Y1038443D01*
Y1026146D01*
X42924Y1026145D01*
Y1023920D01*
X40888Y1021731D01*
Y1017148D01*
X38672Y1014932D01*
Y863605D01*
X32572Y857505D01*
Y836683D01*
X30661Y834772D01*
Y815388D01*
X31699Y814350D01*
G01X65500Y817700D02*
Y821771D01*
X62960Y824311D01*
Y830136D01*
X71387Y838563D01*
Y845452D01*
X70474Y846365D01*
Y974546D01*
X84362Y988434D01*
Y1004446D01*
X82562Y1006246D01*
Y1010754D01*
X83119Y1011311D01*
Y1014253D01*
X83118Y1014254D01*
Y1191861D01*
X84228Y1192972D01*
X85063Y1193807D01*
Y1249581D01*
X74095Y1260549D01*
Y1373962D01*
X88613Y1388480D01*
Y1407931D01*
X73650Y1422894D01*
Y1484900D01*
X73649Y1484901D01*
Y1485135D01*
X72493Y1486291D01*
Y1556615D01*
X69562Y1559546D01*
Y1566795D01*
X69199Y1567158D01*
Y1626530D01*
X86650Y1643981D01*
Y1649105D01*
X86838Y1650049D01*
Y1651763D01*
X86650Y1652707D01*
Y1657878D01*
X68972Y1675556D01*
Y1753877D01*
X47499Y1775350D01*
G01X46499Y1836550D02*
X45536Y1837513D01*
X31439D01*
X24211Y1830285D01*
Y1820118D01*
X28647Y1815682D01*
X28685Y1815490D01*
Y1804212D01*
X28647Y1804020D01*
X20203Y1795576D01*
Y1725183D01*
X37786Y1707600D01*
Y1605629D01*
X36487Y1604330D01*
Y1590974D01*
X34544Y1589031D01*
Y1562636D01*
X31233Y1559325D01*
Y1554212D01*
X33535Y1551910D01*
Y1538777D01*
X34124Y1538188D01*
Y1533537D01*
X34175Y1533413D01*
X34176Y1533411D01*
X34177Y1533407D01*
X34190Y1533340D01*
X34248Y1533048D01*
Y1527267D01*
X37887Y1523628D01*
Y1473188D01*
X39925Y1471150D01*
Y1447806D01*
X38110Y1445991D01*
Y1059883D01*
X38109Y1059882D01*
Y1040748D01*
X41150Y1037707D01*
Y1026882D01*
X41149Y1026881D01*
Y1024620D01*
X39113Y1022429D01*
Y1017884D01*
X36896Y1015667D01*
Y1014197D01*
X36897Y1014196D01*
Y867327D01*
X25782Y856212D01*
X24218D01*
X23112Y857318D01*
Y858882D01*
X23299Y859069D01*
Y863050D01*
G01X43099Y1833850D02*
X55450Y1821498D01*
Y1772421D01*
X72522Y1755349D01*
Y1677028D01*
X90200Y1659350D01*
Y1653059D01*
X90388Y1652115D01*
Y1649697D01*
X90200Y1648753D01*
Y1642509D01*
X72749Y1625058D01*
Y1568642D01*
X73112Y1568279D01*
Y1561018D01*
X77112Y1557018D01*
Y1544952D01*
X80207Y1541857D01*
Y1421359D01*
X92163Y1409403D01*
Y1387008D01*
X91238Y1386083D01*
Y1361867D01*
X80617Y1351246D01*
Y1331044D01*
X88613Y1323048D01*
Y1011783D01*
X86112Y1009282D01*
Y1007718D01*
X87912Y1005918D01*
Y986962D01*
X74220Y973270D01*
Y854150D01*
G01X39699Y1833850D02*
X53675Y1819874D01*
Y1771685D01*
X70747Y1754613D01*
Y1676292D01*
X88425Y1658614D01*
Y1652883D01*
X88613Y1651939D01*
Y1649873D01*
X88425Y1648929D01*
Y1643245D01*
X70974Y1625794D01*
Y1567900D01*
X71337Y1567537D01*
Y1560282D01*
X74311Y1557308D01*
Y1486984D01*
X75424Y1485871D01*
Y1485637D01*
X75425Y1485636D01*
Y1436275D01*
X77888Y1433812D01*
Y1421167D01*
X90388Y1408667D01*
Y1387744D01*
X75870Y1373226D01*
Y1356960D01*
X77242Y1355588D01*
X78072D01*
X79354Y1354306D01*
Y1352494D01*
X78842Y1351982D01*
Y1328752D01*
X86838Y1320756D01*
Y1012519D01*
X84337Y1010018D01*
Y1006982D01*
X86137Y1005182D01*
Y987698D01*
X72332Y973893D01*
Y849580D01*
X72362Y849550D01*
G01X105100Y600000D02*
X103702Y601398D01*
Y909298D01*
X93000Y920000D01*
Y959000D01*
X99000Y965000D01*
G01X90000Y993100D02*
Y1010659D01*
X90388Y1011047D01*
Y1323784D01*
X90000Y1324172D01*
Y1324828D01*
X82392Y1332436D01*
Y1348989D01*
X93013Y1359610D01*
Y1385347D01*
X95451Y1387785D01*
Y1405682D01*
X95452Y1405683D01*
Y1408625D01*
X81982Y1422095D01*
Y1495417D01*
X82237Y1495672D01*
Y1500428D01*
X81982Y1500683D01*
Y1542752D01*
X80043Y1544691D01*
G01X83932Y1544705D02*
Y1501244D01*
X84012Y1501164D01*
Y1494936D01*
X83932Y1494856D01*
Y1422656D01*
X103098Y1403490D01*
Y1370548D01*
X96050Y1363500D01*
Y1339950D01*
X92618Y1336518D01*
Y1243562D01*
X92600Y1243472D01*
Y996100D01*
G01X76999Y1196550D02*
Y1234101D01*
X66995Y1244105D01*
Y1393283D01*
X76611Y1402899D01*
Y1409889D01*
X66037Y1420463D01*
Y1434831D01*
X66550Y1435344D01*
Y1482190D01*
X65393Y1483347D01*
Y1553471D01*
X65237Y1553827D01*
X62462Y1556602D01*
Y1563824D01*
X61872Y1564414D01*
Y1636103D01*
X61185Y1636790D01*
Y1742264D01*
X45799Y1757650D01*
G01X20999Y1352050D02*
X21499Y1351550D01*
Y1321050D01*
X20999Y1320550D01*
G01X90324Y1538800D02*
Y1421576D01*
X108000Y1403900D01*
Y1368500D01*
X105100Y1365600D01*
Y1323763D01*
X102700Y1321363D01*
G01X102100Y968500D02*
Y968605D01*
X113650Y980155D01*
Y1050650D01*
X125000Y1062000D01*
Y1066500D01*
X127500Y1069000D01*
X142500D01*
X145951Y1072451D01*
Y1108892D01*
X97200Y1157643D01*
Y1309500D01*
X114200Y1326500D01*
Y1337500D01*
X117300Y1340600D01*
Y1363800D01*
X115400Y1365700D01*
Y1399600D01*
X92700Y1422300D01*
Y1549751D01*
X97499Y1554550D01*
G01X99000Y965000D02*
X99900Y965900D01*
Y969163D01*
X111700Y980963D01*
Y1051700D01*
X122000Y1062000D01*
Y1068000D01*
X125500Y1071500D01*
X141000D01*
X144000Y1074500D01*
Y1108084D01*
X95250Y1156834D01*
Y1335850D01*
X98000Y1338600D01*
Y1362692D01*
X106100Y1370792D01*
Y1402999D01*
X86424Y1422675D01*
Y1547475D01*
X96999Y1558050D01*
G01X78600Y1561900D02*
X77102Y1563398D01*
Y1571138D01*
X80164Y1574200D01*
X90200D01*
X103475Y1587475D01*
X333827D01*
X338700Y1592348D01*
X930171D01*
X930273Y1592450D01*
X930275D01*
X942540Y1604716D01*
X954764Y1616942D01*
X969487Y1631665D01*
Y1631666D01*
X973130Y1635309D01*
Y1641219D01*
X976000Y1644089D01*
Y1659000D01*
X977500Y1660500D01*
G01X75000Y1561800D02*
Y1571547D01*
X79853Y1576400D01*
X89400D01*
X102275Y1589275D01*
X332974D01*
X337924Y1594225D01*
X929539D01*
X956434Y1621124D01*
X956435D01*
X967712Y1632401D01*
Y1639082D01*
X974100Y1645470D01*
Y1664100D01*
X978000Y1668000D01*
G01X74800Y1584700D02*
X92189D01*
X100314Y1592825D01*
X100910D01*
X100911Y1592826D01*
X103790D01*
X103791Y1592825D01*
X331502D01*
X336452Y1597775D01*
X928065D01*
X928067Y1597777D01*
X928069D01*
X964100Y1633814D01*
Y1639100D01*
X964000Y1639200D01*
G01X960900Y1636400D02*
X961702Y1635598D01*
Y1633927D01*
X927333Y1599552D01*
X927331D01*
X927329Y1599550D01*
X335716D01*
X330766Y1594600D01*
X104527D01*
X104526Y1594601D01*
X100175D01*
X100174Y1594600D01*
X96600D01*
X74524Y1616676D01*
Y1624321D01*
X85486Y1635283D01*
Y1635284D01*
X91975Y1641773D01*
Y1648577D01*
X92163Y1649521D01*
Y1652291D01*
X91975Y1653235D01*
Y1660086D01*
X74500Y1677561D01*
Y1692000D01*
G01X74700Y1574600D02*
Y1575100D01*
X77950Y1578350D01*
X88350D01*
X101050Y1591050D01*
X332238D01*
X337188Y1596000D01*
X928801D01*
X928803Y1596002D01*
X928805D01*
X965937Y1633140D01*
Y1642938D01*
X969670Y1646671D01*
Y1647282D01*
X969900Y1647512D01*
Y1666600D01*
X974000Y1670700D01*
G01X89373Y1561073D02*
X112225Y1583925D01*
X335314D01*
X340164Y1588775D01*
X931622D01*
X959487Y1616642D01*
X976112Y1633267D01*
X976680Y1633836D01*
Y1639555D01*
X979725Y1642600D01*
Y1651225D01*
X981500Y1653000D01*
G01X85600Y1561500D02*
X109800Y1585700D01*
X334578D01*
X339428Y1590550D01*
X930886D01*
X931011Y1590675D01*
X944316Y1603981D01*
X961991Y1621657D01*
X974905Y1634572D01*
Y1640483D01*
X977775Y1643353D01*
Y1656575D01*
X980800Y1659600D01*
G01X39000Y1750800D02*
X37958Y1751842D01*
Y1779257D01*
X39324Y1780623D01*
G01X42275Y1754000D02*
X41671Y1754604D01*
Y1777789D01*
X43751Y1779869D01*
Y1780559D01*
G01X48049Y1791450D02*
X49787Y1793188D01*
Y1804013D01*
X42448Y1811352D01*
Y1814500D01*
X42021Y1814928D01*
X34099Y1822850D01*
G01X46999Y1779550D02*
X47250D01*
X51900Y1784200D01*
Y1818979D01*
X37811Y1833068D01*
Y1834632D01*
X38917Y1835738D01*
X44641D01*
X63129Y1817250D01*
X80099D01*
G01X41200Y1747050D02*
X38550D01*
X36178Y1749422D01*
Y1780928D01*
X38094Y1782845D01*
Y1785840D01*
G01X199900Y554050D02*
X161450D01*
X154500Y561000D01*
Y584551D01*
X165700Y595751D01*
Y750876D01*
X156026Y760550D01*
Y836823D01*
X154799Y838050D01*
G01X137899Y545451D02*
X121200Y562150D01*
Y803000D01*
X150500Y832300D01*
X153800D01*
X153900Y832200D01*
G01X150750Y540416D02*
X829917Y216200D01*
G01X833576Y215432D02*
X830454Y218554D01*
X151900Y542366D01*
X149942D01*
X148800Y541224D01*
Y537700D01*
X149000Y537500D01*
G01X107000Y604800D02*
Y605400D01*
X106000Y606400D01*
Y911500D01*
X95500Y922000D01*
Y958000D01*
X102000Y964500D01*
Y968400D01*
X102100Y968500D01*
G01X164700Y1085400D02*
Y1085980D01*
X167270Y1088550D01*
X213050D01*
X222500Y1098000D01*
X232750D01*
X240650Y1090100D01*
X329049D01*
X337999Y1099050D01*
X364499D01*
G01X251500Y1136700D02*
X150700D01*
X138600Y1124600D01*
G01X107999Y1307713D02*
X112313D01*
X114575Y1309975D01*
X341924D01*
X341999Y1310050D01*
X345424D01*
G01X120507Y1317050D02*
X125007Y1312550D01*
X156599D01*
X167099Y1323050D01*
X367149D01*
X370149Y1320050D01*
G01X119499Y1339050D02*
Y1362991D01*
X120508Y1364000D01*
X121000D01*
G01X279999Y1556050D02*
X172050D01*
X152450Y1536450D01*
X100800D01*
G01X96200Y1550100D02*
X95900Y1549800D01*
Y1532600D01*
X98000Y1530500D01*
X152000D01*
X160500Y1539000D01*
X319050D01*
X343652Y1514398D01*
X390999D01*
G01X99899Y1539850D02*
X153150D01*
X172300Y1559000D01*
X354000D01*
X354500Y1559500D01*
G01X100000Y1546650D02*
Y1546939D01*
X108625Y1555564D01*
Y1561405D01*
X127595Y1580375D01*
X336625D01*
X336900Y1580100D01*
X396449D01*
X400999Y1575550D01*
G01X98144Y1534309D02*
X97774Y1534679D01*
Y1547224D01*
X106850Y1556300D01*
Y1562141D01*
X126859Y1582150D01*
X336050D01*
X340900Y1587000D01*
X932358D01*
X974775Y1629419D01*
X978455Y1633099D01*
Y1638105D01*
X982050Y1641700D01*
Y1649302D01*
G01X157400Y1596550D02*
X162000D01*
X711652Y1822109D01*
G01X160200Y1598500D02*
X711848Y1825504D01*
G01X152633Y1677967D02*
X147833D01*
X122642Y1703158D01*
Y1704243D01*
G01X377900Y1703800D02*
X329600D01*
X305912Y1680112D01*
X149267D01*
X126861Y1702518D01*
Y1702694D01*
X120400Y1709155D01*
Y1712775D01*
X112562Y1720613D01*
G01X218499Y190550D02*
X292999Y265050D01*
Y292550D01*
X293999Y293550D01*
G01X211750Y894600D02*
X213850Y892500D01*
X367500D01*
X371500Y888500D01*
Y880600D01*
G01X340699Y1046086D02*
X339735Y1047050D01*
X269050D01*
X240075Y1076025D01*
X228794D01*
X228769Y1076000D01*
X228500D01*
X221800Y1069300D01*
G01X295000Y1513000D02*
X291500Y1509500D01*
Y1448500D01*
X205900Y1362900D01*
X199149D01*
G01X330540Y795509D02*
X342149Y783900D01*
Y728851D01*
X408106Y662894D01*
X465906D01*
X787600Y341200D01*
X788800D01*
X793900Y336100D01*
Y332000D01*
X784950Y323050D01*
X772499D01*
G01X394649Y630600D02*
X335624Y689625D01*
Y782925D01*
X320499Y798050D01*
G01X771105Y722789D02*
X408260D01*
X329499Y801550D01*
G01X283499Y1556050D02*
X284149Y1556700D01*
X363674D01*
X366149Y1554225D01*
Y1554050D01*
G01X344520Y406329D02*
X400499D01*
G01X791499Y333050D02*
X788350D01*
X572500Y548900D01*
X372399D01*
X371999Y549300D01*
G01X791999Y733050D02*
Y732199D01*
X781200Y721400D01*
X778700D01*
X754600Y697300D01*
X748700D01*
X747450Y698550D01*
X375999D01*
G01X792154Y1135926D02*
X790778Y1134550D01*
X771999D01*
X760999Y1123550D01*
X372999D01*
G01X771999Y1124550D02*
X743999Y1096550D01*
X345499D01*
G01X347324Y1524000D02*
X347874Y1524550D01*
X740050D01*
X746500Y1531000D01*
X773592D01*
X774542Y1530050D01*
G01X390999Y1517798D02*
X391251Y1518050D01*
X736334D01*
X747384Y1529100D01*
X771025D01*
X772325Y1527800D01*
X779450D01*
X792700Y1541050D01*
X793999D01*
G01X349774Y1582900D02*
X933280D01*
X979366Y1628986D01*
X980350Y1629971D01*
X982005Y1631627D01*
Y1634907D01*
X986400Y1639302D01*
G01X354000Y1584900D02*
X932769D01*
X933221Y1585352D01*
X976004Y1628136D01*
X978123Y1630255D01*
X979094Y1631227D01*
X980230Y1632364D01*
Y1637369D01*
X984211Y1641350D01*
Y1667500D01*
G54D11*
X17720Y1903144D03*
X29532Y309561D03*
Y1029522D03*
X271657Y267711D03*
Y673223D03*
Y1078734D03*
Y1484246D03*
Y1889758D03*
X994098Y149601D03*
Y673223D03*
X994099Y1068892D03*
G54D12*
X68898Y17047D03*
Y190275D03*
Y422559D03*
Y595787D03*
Y828071D03*
Y1233583D03*
Y1406811D03*
Y1812323D03*
X167323Y179803D03*
Y353031D03*
Y585315D03*
Y758543D03*
Y990827D03*
Y1164055D03*
Y1396339D03*
Y1569567D03*
Y1801851D03*
Y1975079D03*
X895669Y179803D03*
Y353031D03*
Y585315D03*
Y758543D03*
Y990827D03*
Y1164055D03*
Y1396339D03*
Y1569567D03*
Y1801851D03*
Y1975079D03*
G54D13*
X93999Y58550D03*
X92900Y66128D03*
X89800Y132400D03*
X92999Y86128D03*
Y96128D03*
X41999Y200050D03*
X65999Y216050D03*
X95350Y204550D03*
X89800Y208550D03*
X24300Y247300D03*
X29699Y388484D03*
X29599Y382884D03*
X29999Y398684D03*
X23499Y397579D03*
X23399Y373931D03*
Y389679D03*
X23499Y381831D03*
X28100Y374000D03*
X26299Y478404D03*
X26515Y481798D03*
X26486Y462648D03*
X26499Y466250D03*
X29899Y404384D03*
X28900Y429200D03*
X29500Y460800D03*
X28700Y451900D03*
X28800Y436700D03*
X28700Y445700D03*
X68000Y475600D03*
X67800Y469900D03*
X23499Y468447D03*
X23399Y476295D03*
Y444799D03*
X23499Y452699D03*
X23399Y460547D03*
Y429051D03*
X23499Y436951D03*
X23600Y405700D03*
X77499Y469550D03*
X61400Y452600D03*
X65000Y455500D03*
X28900Y417800D03*
X83700Y529500D03*
X28600Y508500D03*
X38400Y514900D03*
X88999Y538050D03*
X68900Y490600D03*
X68700Y485200D03*
X28600Y499300D03*
X63499Y538550D03*
Y533050D03*
X22800Y539600D03*
X23499Y515691D03*
X23399Y492043D03*
X23499Y499943D03*
X23399Y507791D03*
X23499Y484195D03*
X77999Y493050D03*
X77499Y502550D03*
X26599Y525648D03*
X95500Y513400D03*
X26599Y529302D03*
X68000Y546500D03*
X72500Y545000D03*
X27199Y539600D03*
X42202Y608195D03*
X41400Y611500D03*
X41500Y642800D03*
X32800Y578200D03*
X47543Y578340D03*
X44959Y575756D03*
X30712Y624971D03*
X29999Y640550D03*
X60076Y595777D03*
X55499Y595650D03*
X29819Y634951D03*
X26869Y616861D03*
X23399Y641649D03*
X23499Y618053D03*
X23799Y625950D03*
X23499Y633801D03*
X23999Y609250D03*
X22978Y588571D03*
X22699Y577950D03*
X22999Y565550D03*
X57800Y634300D03*
X34976Y619250D03*
X44900Y642800D03*
X47101Y632355D03*
X26800Y611500D03*
X41500Y635000D03*
X30999Y656250D03*
X29999Y694550D03*
X30999Y650550D03*
X81999Y668050D03*
X74499Y662050D03*
X25999Y694870D03*
X23499Y649549D03*
X23725Y657471D03*
X78499Y654050D03*
X27700Y682700D03*
X44046Y799554D03*
X37416Y799033D03*
X37099Y811350D03*
X51100Y806300D03*
X56281Y801350D03*
X35300Y789375D03*
X35559Y795112D03*
X37216Y807951D03*
X76540Y850938D03*
X75500Y847700D03*
X49300Y836500D03*
X46700Y820100D03*
X58699Y837250D03*
X92999Y868550D03*
X92499Y876550D03*
X68860Y838706D03*
X69499Y842950D03*
X62405Y820300D03*
X63499Y843050D03*
X31699Y814350D03*
X65500Y817700D03*
X23299Y863050D03*
X26662Y861550D03*
X80500Y817000D03*
X74220Y854150D03*
X72362Y849550D03*
X89400Y935400D03*
X89499Y942850D03*
X90000Y993100D03*
X92600Y996100D03*
X20400Y1048300D03*
X76999Y1196550D03*
X78499Y1273550D03*
X78613Y1282664D03*
X78779Y1302664D03*
X91279Y1340642D03*
X89999Y1348050D03*
X27499Y1387550D03*
X24499Y1389663D03*
X22851Y1374169D03*
X22999Y1366050D03*
X23700Y1354600D03*
X23499Y1381500D03*
X78779Y1312664D03*
X86165Y1339050D03*
X20999Y1352050D03*
Y1320550D03*
X33000Y1393000D03*
X33400Y1408100D03*
X36198Y1446749D03*
X26800Y1443800D03*
X30600Y1415100D03*
X30999Y1438050D03*
X27999Y1430050D03*
X29100Y1459200D03*
X34200Y1466200D03*
X23028Y1468579D03*
X23499Y1460550D03*
X22999Y1453050D03*
X23499Y1445050D03*
X22999Y1437050D03*
X23999Y1429050D03*
X23499Y1421550D03*
X23999Y1413550D03*
X80043Y1544691D03*
X83932Y1544705D03*
X96200Y1550100D03*
X32700Y1485200D03*
X28999Y1478050D03*
X27100Y1494300D03*
X34900Y1501000D03*
X35400Y1522200D03*
X35999Y1514550D03*
X29600Y1515300D03*
X24423Y1527123D03*
X22999Y1500050D03*
Y1515550D03*
X23799Y1508050D03*
X24499Y1492050D03*
X23599Y1476350D03*
X23277Y1484050D03*
X25247Y1546912D03*
X90324Y1538800D03*
X78600Y1561900D03*
X75000Y1561800D03*
X38208Y1569841D03*
X24900Y1569500D03*
X31149Y1568300D03*
X26999Y1610550D03*
X34884Y1615734D03*
X32199Y1633124D03*
X34816Y1630953D03*
X22999Y1626050D03*
X23499Y1634050D03*
Y1618050D03*
X22699Y1594224D03*
X23499Y1610050D03*
Y1602050D03*
X23608Y1572653D03*
X24323Y1559950D03*
X31099Y1595350D03*
X74800Y1584700D03*
X74700Y1574600D03*
X39000Y1573500D03*
X89373Y1561073D03*
X85600Y1561500D03*
X33100Y1648500D03*
X34699Y1663300D03*
X27499Y1657050D03*
X26785Y1642089D03*
X22999Y1665550D03*
X92873Y1708176D03*
X24244Y1681868D03*
X22864Y1673550D03*
X23499Y1657050D03*
X23999Y1649550D03*
X23415Y1641634D03*
X92479Y1718176D03*
X78100Y1688189D03*
X92900Y1678176D03*
X74500Y1692000D03*
X30274Y1787238D03*
X38878Y1799571D03*
X36300Y1805123D03*
X35675Y1783450D03*
X39324Y1780623D03*
X39000Y1750800D03*
X43751Y1780559D03*
X42275Y1754000D03*
X48049Y1791450D03*
X89306Y1746856D03*
X89499Y1753575D03*
X46999Y1779550D03*
X38094Y1785840D03*
X41200Y1747050D03*
X45799Y1757650D03*
X47440Y1761391D03*
X43559Y1767884D03*
X32099Y1797150D03*
X47604Y1769005D03*
X45782Y1771877D03*
X47499Y1775350D03*
X28550Y1828153D03*
X29899Y1821050D03*
X34099Y1822850D03*
X60449Y1842550D03*
X80099Y1817250D03*
X26099Y1824950D03*
X46499Y1836550D03*
X47166Y1839884D03*
X90000Y1827900D03*
X43099Y1833850D03*
X39699D03*
X93500Y1827900D03*
X50299Y1946650D03*
X53999D03*
X42532Y1946783D03*
X44399Y1942250D03*
X38703Y1946754D03*
X34799Y1946750D03*
X46565Y1946703D03*
X44368Y1951450D03*
X45999Y1971450D03*
X28799Y1919060D03*
X14999Y1940050D03*
X112999Y124050D03*
X111790Y132259D03*
X152499Y149550D03*
X173499Y149050D03*
X175999Y82428D03*
X127999Y157050D03*
X114900Y177900D03*
X154200Y168500D03*
X149400Y166400D03*
X147099Y245350D03*
X124999Y246050D03*
X123300Y256000D03*
X157440Y283924D03*
Y303924D03*
Y313924D03*
X166500Y428500D03*
X153459Y427494D03*
X154101Y445550D03*
X102100Y514900D03*
X163449Y521650D03*
X107526Y528996D03*
X104502Y530552D03*
X138999Y524213D03*
X173100Y483100D03*
X168453Y527949D03*
X160932Y549468D03*
X98900Y513400D03*
X137899Y545451D03*
X150750Y540416D03*
X149000Y537500D03*
X127999Y645550D03*
X131400Y644600D03*
X161000Y639100D03*
X124999Y643050D03*
X129000Y636600D03*
X128600Y640500D03*
X140900Y644000D03*
X134300Y646400D03*
X107000Y604800D03*
X105100Y600000D03*
X157000Y573851D03*
X160824Y577000D03*
X140400Y649800D03*
X158885Y679436D03*
Y689436D03*
X141500Y711000D03*
X158385Y719436D03*
X154799Y838050D03*
X172660Y815731D03*
X174199Y841050D03*
X159500Y814700D03*
X153900Y832200D03*
X98700Y842600D03*
Y822550D03*
X98000Y833500D03*
X163500Y937100D03*
X172500Y919294D03*
X106749Y934367D03*
X108441Y924705D03*
X160399Y922850D03*
X102100Y968500D03*
X99000Y965000D03*
X154749Y968249D03*
X123999Y1054050D03*
Y1050650D03*
X120100Y1053200D03*
X124100Y1047100D03*
X154749Y979149D03*
X164700Y1085400D03*
X137100Y1084800D03*
X140800Y1076300D03*
X121500Y1083600D03*
X121100Y1075300D03*
X116249Y1102550D03*
X112999Y1103740D03*
X117499Y1079300D03*
X157700Y1114948D03*
X157600Y1124948D03*
X159000Y1083000D03*
X127000Y1113500D03*
X138600Y1124600D03*
X114999Y1210363D03*
X130699Y1210653D03*
X118999Y1219050D03*
X107999Y1307713D03*
X120507Y1317050D03*
X101500Y1352000D03*
X113500D03*
X113000Y1341000D03*
X102000D03*
X107228Y1330552D03*
X107500Y1340500D03*
X110499Y1365050D03*
X109999Y1355050D03*
X138000Y1359025D03*
X111499Y1311800D03*
X125999Y1315550D03*
X132999Y1319550D03*
X142667Y1319218D03*
X149562Y1315987D03*
X133475Y1331200D03*
X102700Y1321363D03*
X119499Y1339050D03*
X121000Y1364000D03*
X148024Y1333525D03*
X140000Y1332600D03*
X129000Y1356500D03*
X147400Y1321600D03*
X125100Y1366000D03*
X139815Y1454438D03*
X139235Y1460973D03*
X123999Y1473050D03*
X127898Y1462441D03*
X107300Y1438100D03*
X114499Y1432050D03*
X114000Y1425400D03*
X107999Y1448050D03*
X150338Y1453958D03*
X152499Y1462940D03*
X105099Y1459150D03*
X100800Y1536450D03*
X157440Y1490460D03*
Y1500460D03*
Y1520460D03*
Y1530460D03*
X100499Y1479650D03*
X122199Y1476050D03*
X99899Y1539850D03*
X100000Y1546650D03*
X97499Y1554550D03*
X96999Y1558050D03*
X98144Y1534309D03*
X157400Y1596550D03*
X160200Y1598500D03*
X169100Y1685800D03*
X133090Y1699959D03*
X104999Y1708963D03*
X141500Y1715500D03*
X117249Y1712090D03*
X165575Y1676975D03*
X152633Y1677967D03*
X122642Y1704243D03*
X112562Y1720613D03*
X177900Y1690400D03*
X169600Y1682300D03*
X107300Y1746300D03*
X107100Y1736000D03*
X165900Y1790500D03*
X161900Y1793400D03*
X135999Y1881550D03*
X141300Y1866400D03*
X141800Y1860500D03*
X159421Y1925972D03*
X210638Y62959D03*
X210634Y66863D03*
X201499Y104550D03*
X245499Y100550D03*
X246499Y86050D03*
Y80550D03*
X215138Y72559D03*
X210685Y74725D03*
X210605Y70692D03*
X205938Y72528D03*
X210738Y78459D03*
Y82159D03*
X197899Y165075D03*
X218499Y190550D03*
X213499Y283864D03*
X250300Y275100D03*
X250400Y283100D03*
X239600Y278600D03*
X213400Y355300D03*
X224998Y357049D03*
X233998Y357549D03*
X239400Y357400D03*
X252935Y319114D03*
X214063Y318114D03*
X231800Y318414D03*
X179700Y425800D03*
X199900Y554050D03*
X182499Y532550D03*
X193549Y575875D03*
X216999Y686550D03*
X213999Y725050D03*
X230849Y726050D03*
X252499D03*
X249700Y682500D03*
X249800Y689900D03*
X238500Y680800D03*
X228999Y765550D03*
X218224Y765325D03*
X241600Y765700D03*
X236800Y765800D03*
X199000Y815000D03*
X211750Y894600D03*
X198924Y975975D03*
X229562Y904113D03*
X215499Y905550D03*
X226800Y1093400D03*
X221800Y1069300D03*
X256000Y1133000D03*
X255000Y1125700D03*
X221300Y1083238D03*
X251500Y1136700D03*
X229800Y1073600D03*
X242000Y1066000D03*
X199149Y1362900D03*
X181000Y1365500D03*
X180500Y1369900D03*
X241000Y1469600D03*
X232650Y1493450D03*
X233700Y1481600D03*
X179999Y1655887D03*
X186000Y1644000D03*
X181100Y1682700D03*
X194049Y1792600D03*
X236225Y1883125D03*
X229800Y1875700D03*
X218100Y1886400D03*
X232314Y1890513D03*
X213562Y1926113D03*
X220062Y1931113D03*
X240964Y1934113D03*
X343499Y60150D03*
X296099Y17100D03*
X305099Y17000D03*
X311400Y17100D03*
X317000Y17300D03*
X291999Y94050D03*
X315800Y100500D03*
X324800Y89400D03*
X293999Y293550D03*
X313039Y352350D03*
X321900Y364600D03*
X298800Y333000D03*
X294500Y339000D03*
X344520Y406329D03*
X308999Y716450D03*
X315999Y718950D03*
X329499Y801550D03*
X330540Y795509D03*
X320499Y798050D03*
X292999Y743650D03*
X298000Y743500D03*
X323249Y749010D03*
X324959Y766750D03*
X277039Y740300D03*
X340699Y1046086D03*
X283499Y1556050D03*
X279999D03*
X289999Y1554650D03*
X293700Y1553351D03*
X276039Y1551300D03*
X314999Y1527550D03*
X295000Y1513000D03*
X297800Y1561600D03*
X291400Y1561500D03*
X324000Y1562500D03*
X312999Y1566050D03*
X323999Y1577250D03*
X280689Y1942710D03*
X315999Y1958550D03*
X327100Y1966472D03*
X329999Y1952273D03*
X325221Y1927272D03*
X313499Y1919050D03*
X398799Y36152D03*
X381999Y50150D03*
X386799Y45000D03*
X358999Y61550D03*
X426000Y93500D03*
X357503Y77043D03*
X374499Y77550D03*
X385999Y78050D03*
X401499Y80550D03*
X400499Y406329D03*
X371999Y549300D03*
X394649Y630600D03*
X375999Y698550D03*
X371500Y880600D03*
X364499Y1099050D03*
X372999Y1123550D03*
X345499Y1096550D03*
X370149Y1320050D03*
X345424Y1310050D03*
X347324Y1524000D03*
X366149Y1554050D03*
X390999Y1514398D03*
Y1517798D03*
X349774Y1582900D03*
X354500Y1559500D03*
X400999Y1575550D03*
X354000Y1584900D03*
X377900Y1703800D03*
X367000Y1810000D03*
X360000Y1967500D03*
X659549Y1810634D03*
X757499Y745342D03*
X755600Y1149800D03*
X758499Y1371050D03*
X754000Y1551000D03*
X690249Y1805634D03*
X755000Y1825000D03*
X711652Y1822109D03*
X711848Y1825504D03*
X752500Y1954500D03*
X821999Y193116D03*
X827499Y163550D03*
X820749Y163850D03*
X813249Y163800D03*
X839249Y164050D03*
X829917Y216200D03*
X833576Y215432D03*
X770999Y302050D03*
X785499Y291050D03*
X770999Y290050D03*
Y295550D03*
X827499Y313424D03*
X763571Y295622D03*
X777999Y296050D03*
X786978Y298529D03*
X836500Y274950D03*
X812500Y282750D03*
X822100Y261700D03*
X816700Y274300D03*
X791499Y333050D03*
X772499Y323050D03*
X758778Y345000D03*
X768178Y333964D03*
X784499Y334050D03*
X771105Y722789D03*
X835150Y677650D03*
X806500Y687250D03*
X820600Y664300D03*
X813200Y675900D03*
X791999Y733050D03*
X766499Y732842D03*
X762500Y734000D03*
X784939Y733550D03*
X792154Y1135926D03*
X771999Y1124550D03*
X767083Y1134550D03*
X764549Y1138500D03*
X784439Y1136550D03*
X814000Y1087000D03*
X825800Y1072300D03*
X815400Y1078800D03*
X822100Y1466800D03*
X774542Y1530050D03*
X836625Y1487400D03*
X771225Y1539474D03*
X767936Y1540336D03*
X784577Y1535628D03*
X812550Y1494050D03*
X793999Y1541050D03*
X814700Y1486300D03*
X788000Y1788000D03*
X774500D03*
X812000Y1799500D03*
X821249Y1791250D03*
X811000Y1793000D03*
X770999Y1820550D03*
X822499Y1815164D03*
X791999Y1819050D03*
X783499Y1827050D03*
X822700Y1871100D03*
X805900Y1887560D03*
X767999Y1945173D03*
X764908Y1946592D03*
X785939Y1946800D03*
X812500Y1898500D03*
X919800Y54600D03*
X924200Y69800D03*
X898800Y96000D03*
X855500Y149500D03*
X873000Y148500D03*
X846500Y149500D03*
X841499Y135550D03*
X861999Y146550D03*
X882499Y147050D03*
X896999Y141550D03*
X916499Y115050D03*
X923761Y85550D03*
X867500Y163924D03*
X867576Y159924D03*
X847500Y246600D03*
X850999Y246550D03*
X874700Y244900D03*
X874900Y238600D03*
X871999Y283924D03*
X886200Y313924D03*
X886600Y303924D03*
X872136Y273924D03*
X858478Y274050D03*
X875100Y644400D03*
X922049Y574375D03*
X879750Y570550D03*
X879950Y565050D03*
X875300Y650500D03*
X851300Y651700D03*
X847600Y651600D03*
X922049Y978575D03*
X879708Y971892D03*
X847500Y1057800D03*
X851000Y1058000D03*
X874733Y1055792D03*
X874999Y1049550D03*
X883083Y979183D03*
X871499Y1124948D03*
X872086Y1114948D03*
X871999Y1094948D03*
X872086Y1084948D03*
X860133Y1084142D03*
X860799Y1358925D03*
X866700Y1379796D03*
X866596Y1375796D03*
X874100Y1461600D03*
X874900Y1454000D03*
X848861Y1462463D03*
X852500Y1462600D03*
X858827Y1485696D03*
X872086Y1490460D03*
X871999Y1500460D03*
Y1520460D03*
X872086Y1530460D03*
X900500Y1721500D03*
X921549Y1788475D03*
X879700Y1786300D03*
X879664Y1782213D03*
X851500Y1821400D03*
X849375Y1824982D03*
X854905Y1825583D03*
X854480Y1867578D03*
X849999Y1867550D03*
X863700Y1867300D03*
X865300Y1858700D03*
X859314Y1891365D03*
X871921Y1905972D03*
X871421Y1895972D03*
X872086Y1925972D03*
Y1935972D03*
X961499Y100050D03*
X946899Y122550D03*
X932961Y85581D03*
X928461Y75981D03*
X928561Y91481D03*
X928508Y87747D03*
X928428Y83714D03*
X928561Y95181D03*
X928457Y79885D03*
X958999Y96050D03*
X939549Y175175D03*
X966499Y552050D03*
X965999Y954550D03*
X986400Y1639302D03*
X990425Y1633898D03*
X987029Y1634075D03*
X981200Y1618002D03*
X964000Y1639200D03*
X960900Y1636400D03*
X977500Y1660500D03*
X978000Y1668000D03*
X989502Y1646000D03*
X988800Y1658300D03*
X989000Y1663802D03*
X987200Y1675600D03*
X989900Y1678800D03*
X974000Y1670700D03*
X984211Y1667500D03*
X981500Y1653000D03*
X980800Y1659600D03*
X982050Y1649302D03*
G54D14*
X129920Y17716D03*
X994093Y1889751D03*
G54D15*
G01X-71137Y-139897D02*
Y-219897D01*
G01D02*
X1129963D01*
G01X-75137Y-123897D02*
G02I-12000J0D01*
G01X-80287D02*
G02I-6850J0D01*
G01X-87137Y-139897D02*
Y-107897D01*
G01X-71137Y-123897D02*
X-103137D01*
G01X-71137Y-139897D02*
X1129963D01*
G01X-71137Y-175397D02*
X1129963D01*
G01X95350Y204550D02*
X97600D01*
X147361Y154789D01*
X261511D01*
X315800Y100500D01*
G01X89800Y208550D02*
X98126D01*
X148687Y157989D01*
X262837D01*
X321300Y99526D01*
Y92400D01*
X324300Y89400D01*
X324800D01*
G01X90000Y1827900D02*
Y1828926D01*
X92874Y1831800D01*
X99003D01*
X158700Y1772103D01*
Y1706373D01*
X174673Y1690400D01*
X177900D01*
G01X93500Y1827900D02*
X94200Y1828600D01*
X97677D01*
X155500Y1770777D01*
Y1705047D01*
X172300Y1688247D01*
Y1684473D01*
X170427Y1682600D01*
X169900D01*
X169600Y1682300D01*
G01X154200Y168500D02*
X169829D01*
X171529Y170200D01*
X176965D01*
X242050Y235285D01*
Y274250D01*
X250400Y282600D01*
Y283100D01*
G01X149400Y166400D02*
Y168700D01*
X152500Y171800D01*
X168603D01*
X170203Y173400D01*
X175639D01*
X238850Y236611D01*
Y275576D01*
X239600Y276326D01*
Y278600D01*
G01X249800Y689900D02*
Y688200D01*
X241700Y680100D01*
Y636339D01*
X212599Y607238D01*
Y606522D01*
X209027Y602950D01*
X208311D01*
X181035Y575674D01*
Y575673D01*
X179162Y573800D01*
X159497D01*
X159446Y573851D01*
X157000D01*
G01X160824Y577000D02*
X177835D01*
X206985Y606150D01*
X207701D01*
X209399Y607848D01*
Y608564D01*
X238500Y637665D01*
Y680800D01*
G01X242000Y1066000D02*
X233000Y1057000D01*
Y1042900D01*
X158349Y968249D01*
X154749D01*
G01X229800Y1073600D02*
Y1044226D01*
X164723Y979149D01*
X154749D01*
G01X140000Y1332600D02*
X131899Y1340701D01*
Y1353601D01*
X129000Y1356500D01*
G01X147400Y1321600D02*
X150624Y1324824D01*
Y1330892D01*
X151725Y1331993D01*
Y1335057D01*
X150624Y1336158D01*
Y1362376D01*
X145800Y1367200D01*
X126300D01*
X125100Y1366000D01*
G01X169100Y1685800D02*
X147249D01*
X133090Y1699959D01*
G01X172499Y1714050D02*
X181100Y1705449D01*
Y1682700D01*
G01X165900Y1790500D02*
X166100Y1790300D01*
X184265D01*
X220550Y1826585D01*
Y1868400D01*
X227850Y1875700D01*
X229800D01*
G01X218100Y1886400D02*
X217350Y1885650D01*
Y1828299D01*
X182751Y1793700D01*
X162200D01*
X161900Y1793400D01*
G01X267498Y295114D02*
X250300Y277916D01*
Y275100D01*
G01X268499Y701550D02*
X249700Y682751D01*
Y682500D01*
G01X241000Y1469600D02*
X184600Y1413200D01*
Y1369100D01*
X181000Y1365500D01*
G01X233700Y1481600D02*
Y1466826D01*
X181400Y1414526D01*
Y1370800D01*
X180500Y1369900D01*
G01X342463Y-139897D02*
Y-219897D01*
G01X479963Y-139897D02*
Y-219897D01*
G01X594963Y-139897D02*
Y-219897D01*
G01X762463Y-139897D02*
Y-219897D01*
G01X822100Y261700D02*
Y248500D01*
X858700Y211900D01*
Y172724D01*
X867500Y163924D01*
G01X816700Y274300D02*
X818900Y272100D01*
Y247174D01*
X855500Y210574D01*
Y171398D01*
X866974Y159924D01*
X867576D01*
G01X879750Y570550D02*
X877915D01*
X820600Y627865D01*
Y664300D01*
G01X813200Y675900D02*
X817400Y671700D01*
Y626539D01*
X876589Y567350D01*
X877650D01*
X879950Y565050D01*
G01X883083Y979183D02*
X875882D01*
X825800Y1029265D01*
Y1072300D01*
G01X879708Y971892D02*
X875617Y975983D01*
X874556D01*
X822600Y1027939D01*
Y1071900D01*
X815700Y1078800D01*
X815400D01*
G01X866700Y1379796D02*
Y1379800D01*
X822100Y1424400D01*
Y1466800D01*
G01X814700Y1486300D02*
X818899Y1482101D01*
Y1423071D01*
X866174Y1375796D01*
X866596D01*
G01X879700Y1786300D02*
X822700Y1843300D01*
Y1871100D01*
G01X805900Y1887560D02*
X810660D01*
X815500Y1882720D01*
Y1845974D01*
X879261Y1782213D01*
X879664D01*
G01X932463Y-139897D02*
Y-219897D01*
G01X1129963Y-139897D02*
Y-219897D01*
G01X1157963Y-123897D02*
G02I-12000J0D01*
G01X1152813D02*
G02I-6850J0D01*
G01X1145963Y-139897D02*
Y-107897D01*
G01X1161963Y-123897D02*
X1129963D01*
G54D16*
G01X226800Y1093400D02*
X224500D01*
X180400Y1049300D01*
X151300D01*
G01X123500Y1360300D02*
X126800D01*
X130000Y1363500D01*
X138500D01*
X141500Y1360500D01*
Y1340049D01*
X148024Y1333525D01*
G54D17*
G01X8518Y1903144D02*
X17720D01*
G01X68898Y12645D02*
Y17047D01*
G01D02*
Y21449D01*
G01X62346Y17047D02*
X68898D01*
G01D02*
X75450D01*
G01X68898Y185873D02*
Y190275D01*
G01D02*
Y194677D01*
G01X62346Y190275D02*
X68898D01*
G01D02*
X75450D01*
G01X29532Y300359D02*
Y309561D01*
G01D02*
Y318763D01*
G01X20330Y309561D02*
X29532D01*
G01D02*
X38734D01*
G01X68898Y418157D02*
Y422559D01*
G01D02*
Y426961D01*
G01X62346Y422559D02*
X68898D01*
G01D02*
X75450D01*
G01X68898Y591385D02*
Y595787D01*
G01D02*
Y600189D01*
G01X62346Y595787D02*
X68898D01*
G01D02*
X75450D01*
G01X68898Y823669D02*
Y828071D01*
G01D02*
X75450D01*
G01X29532Y1020320D02*
Y1029522D01*
G01D02*
Y1038724D01*
G01X20330Y1029522D02*
X29532D01*
G01X68898Y1229181D02*
Y1233583D01*
G01D02*
X72174Y1229181D01*
G01X68898Y1402409D02*
Y1406811D01*
G01D02*
Y1411213D01*
G01Y1812323D02*
X75450D01*
G01X68898D02*
X75450Y1807921D01*
G01X17720Y1893942D02*
Y1903144D01*
G01D02*
Y1912346D01*
G01Y1903144D02*
X26922D01*
G01X129920Y7664D02*
Y17716D01*
G01X119868D02*
X129920D01*
G01X167323Y175401D02*
Y179803D01*
G01D02*
Y184205D01*
G01X160771Y179803D02*
X167323D01*
G01D02*
X173875D01*
G01X167323Y348629D02*
Y353031D01*
G01D02*
Y357433D01*
G01X160771Y353031D02*
X167323D01*
G01D02*
X173875D01*
G01X167323Y580913D02*
Y585315D01*
G01D02*
Y589717D01*
G01X160771Y585315D02*
X167323D01*
G01D02*
X173875D01*
G01X167323Y754141D02*
Y758543D01*
G01D02*
Y762945D01*
G01Y758543D02*
X173875D01*
G01X167323Y990827D02*
Y995229D01*
G01X160771Y990827D02*
X167323D01*
G01Y1159653D02*
Y1164055D01*
G01D02*
Y1168457D01*
G01X160771Y1164055D02*
X167323D01*
G01D02*
X173875D01*
G01X167323Y1391937D02*
Y1396339D01*
G01D02*
Y1400741D01*
G01X160771Y1396339D02*
X167323D01*
G01D02*
X173875D01*
G01X167323Y1565165D02*
Y1569567D01*
G01D02*
Y1573969D01*
G01X160771Y1569567D02*
X167323D01*
G01D02*
X173875D01*
G01X167323Y1797449D02*
Y1801851D01*
G01D02*
Y1806253D01*
G01X160771Y1801851D02*
X167323D01*
G01D02*
X173875D01*
G01X167323Y1970677D02*
Y1975079D01*
G01D02*
Y1979481D01*
G01X160771Y1975079D02*
X167323D01*
G01D02*
X173875D01*
G01X271657Y258509D02*
Y267711D01*
G01D02*
Y276913D01*
G01X262455Y267711D02*
X271657D01*
G01D02*
X280859D01*
G01X271657Y664021D02*
Y673223D01*
G01D02*
Y682425D01*
G01X262455Y673223D02*
X271657D01*
G01D02*
X280859D01*
G01X271657Y1069532D02*
Y1078734D01*
G01X262455D02*
X271657D01*
G01D02*
X280859D01*
G01X271657Y1475044D02*
Y1484246D01*
G01D02*
Y1493448D01*
G01X262455Y1484246D02*
X271657D01*
G01D02*
X280859D01*
G01X271657Y1880556D02*
Y1889758D01*
G01D02*
Y1898960D01*
G01X262455Y1889758D02*
X271657D01*
G01D02*
X280859D01*
G01X895669Y175401D02*
Y179803D01*
G01D02*
Y184205D01*
G01X889117Y179803D02*
X895669D01*
G01D02*
X902221D01*
G01X895669Y348629D02*
Y353031D01*
G01D02*
Y357433D01*
G01X889117Y353031D02*
X895669D01*
G01D02*
X902221D01*
G01X895669Y580913D02*
Y585315D01*
G01D02*
Y589717D01*
G01X889117Y585315D02*
X895669D01*
G01D02*
X902221D01*
G01X895669Y754141D02*
Y758543D01*
G01D02*
Y762945D01*
G01X889117Y758543D02*
X895669D01*
G01D02*
X902221D01*
G01X895669Y986425D02*
Y990827D01*
G01D02*
Y995229D01*
G01X889117Y990827D02*
X895669D01*
G01D02*
X902221D01*
G01X895669Y1159653D02*
Y1164055D01*
G01D02*
Y1168457D01*
G01X889117Y1164055D02*
X895669D01*
G01D02*
X902221D01*
G01X895669Y1391937D02*
Y1396339D01*
G01D02*
Y1400741D01*
G01X889117Y1396339D02*
X895669D01*
G01D02*
X902221D01*
G01X895669Y1565165D02*
Y1569567D01*
G01D02*
Y1573969D01*
G01X889117Y1569567D02*
X895669D01*
G01D02*
X902221D01*
G01X895669Y1797449D02*
Y1801851D01*
G01D02*
Y1806253D01*
G01X889117Y1801851D02*
X895669D01*
G01D02*
X902221D01*
G01X895669Y1970677D02*
Y1975079D01*
G01D02*
Y1979481D01*
G01X889117Y1975079D02*
X895669D01*
G01D02*
X902221D01*
G01X994098Y140399D02*
Y149601D01*
G01D02*
Y158803D01*
G01X984896Y149601D02*
X994098D01*
G01D02*
X1003300D01*
G01X994098Y664021D02*
Y673223D01*
G01D02*
Y682425D01*
G01X984896Y673223D02*
X994098D01*
G01D02*
X1003300D01*
G01X994099Y1059690D02*
Y1068892D01*
G01D02*
Y1078094D01*
G01X984897Y1068892D02*
X994099D01*
G01D02*
X1003301D01*
G01X994093Y1879699D02*
Y1889751D01*
G01D02*
Y1899803D01*
G01X984041Y1889751D02*
X994093D01*
G01D02*
X1004145D01*
G54D18*
G01X-89222Y-207897D02*
Y-190397D01*
G01X-80052D02*
Y-207897D01*
G01Y-199147D02*
X-89222D01*
G01X-67137Y-207897D02*
X-68447Y-207605D01*
X-69757Y-206439D01*
X-70631Y-204397D01*
X-71067Y-202064D01*
X-70631Y-199730D01*
X-69757Y-197689D01*
X-68447Y-196522D01*
X-67137Y-196231D01*
X-65827Y-196522D01*
X-64517Y-197689D01*
X-63644Y-199730D01*
X-63425Y-202064D01*
X-63644Y-204397D01*
X-64517Y-206439D01*
X-65827Y-207605D01*
X-67137Y-207897D01*
G01X-53349D02*
Y-196231D01*
G01Y-199147D02*
X-52475Y-197689D01*
X-51165Y-196522D01*
X-49419Y-196231D01*
X-47891Y-196522D01*
X-46580Y-197689D01*
X-45925Y-199730D01*
Y-207897D01*
G01X-35412Y-200022D02*
X-28425D01*
X-29080Y-197980D01*
X-30172Y-196814D01*
X-31700Y-196231D01*
X-33229Y-196522D01*
X-34539Y-197397D01*
X-35412Y-199439D01*
X-35849Y-201189D01*
Y-202939D01*
X-35412Y-204689D01*
X-34320Y-206439D01*
X-33010Y-207605D01*
X-31482Y-207897D01*
X-29954Y-207314D01*
X-28425Y-205564D01*
G01X-19222Y-213147D02*
X-17912Y-213730D01*
X-16165Y-213147D01*
X-15074Y-211981D01*
X-14200Y-210522D01*
X-12891Y-205856D01*
X-10052Y-196231D01*
G01X-17039D02*
X-12891Y-205856D01*
G01X22109Y-198564D02*
X22983Y-197689D01*
X23638Y-196231D01*
X24075Y-194188D01*
X23638Y-192439D01*
X22765Y-191272D01*
X21236Y-190397D01*
X15341D01*
Y-207897D01*
X22546D01*
X24075Y-206731D01*
X24948Y-204980D01*
X25385Y-202939D01*
X24948Y-200897D01*
X23638Y-199147D01*
X22109Y-198564D01*
X15341D01*
G01X41793Y-207897D02*
Y-196231D01*
G01Y-198272D02*
X40920Y-197106D01*
X39609Y-196522D01*
X38081Y-196231D01*
X36553Y-196814D01*
X35243Y-197980D01*
X34369Y-199730D01*
X33933Y-202064D01*
X34369Y-204397D01*
X35243Y-206147D01*
X36553Y-207314D01*
X38081Y-207897D01*
X39609Y-207605D01*
X40920Y-206731D01*
X41793Y-205564D01*
G01X59293Y-190397D02*
Y-207897D01*
G01Y-205273D02*
X58420Y-206731D01*
X57109Y-207605D01*
X55581Y-207897D01*
X53835Y-207314D01*
X52525Y-205856D01*
X51651Y-204106D01*
X51433Y-202064D01*
X51651Y-200022D01*
X52525Y-198272D01*
X53835Y-196814D01*
X55581Y-196231D01*
X57109Y-196522D01*
X58201Y-197106D01*
X59293Y-198272D01*
G01X69806Y-212272D02*
X71335Y-213439D01*
X73081Y-213730D01*
X74609Y-213439D01*
X75920Y-211981D01*
X76793Y-209939D01*
Y-196231D01*
G01Y-198564D02*
X75920Y-197397D01*
X74609Y-196522D01*
X73081Y-196231D01*
X71335Y-196814D01*
X70243Y-197980D01*
X69369Y-200022D01*
X68933Y-202064D01*
X69151Y-203814D01*
X70025Y-205856D01*
X71335Y-207314D01*
X73081Y-207897D01*
X74391Y-207605D01*
X75920Y-206439D01*
X76793Y-205273D01*
G01X87088Y-200022D02*
X94075D01*
X93420Y-197980D01*
X92328Y-196814D01*
X90800Y-196231D01*
X89271Y-196522D01*
X87961Y-197397D01*
X87088Y-199439D01*
X86651Y-201189D01*
Y-202939D01*
X87088Y-204689D01*
X88180Y-206439D01*
X89490Y-207605D01*
X91018Y-207897D01*
X92546Y-207314D01*
X94075Y-205564D01*
G01X104806Y-207897D02*
Y-196231D01*
G01Y-198564D02*
X105898Y-197397D01*
X106990Y-196522D01*
X108518Y-196231D01*
X109609Y-196522D01*
X110920Y-197397D01*
G01X138060Y-207897D02*
Y-190397D01*
X142426D01*
X144173Y-191272D01*
X145483Y-192439D01*
X146575Y-194188D01*
X147448Y-196231D01*
X147666Y-199147D01*
X147448Y-202064D01*
X146575Y-204106D01*
X145483Y-205856D01*
X144173Y-207022D01*
X142426Y-207897D01*
X138060D01*
G01X155996D02*
Y-190397D01*
X161236D01*
X162983Y-191272D01*
X164293Y-193314D01*
X164730Y-195647D01*
X164293Y-197980D01*
X163201Y-199730D01*
X161236Y-200606D01*
X155996D01*
G01X179609Y-198564D02*
X180483Y-197689D01*
X181138Y-196231D01*
X181575Y-194188D01*
X181138Y-192439D01*
X180265Y-191272D01*
X178736Y-190397D01*
X172841D01*
Y-207897D01*
X180046D01*
X181575Y-206731D01*
X182448Y-204980D01*
X182885Y-202939D01*
X182448Y-200897D01*
X181138Y-199147D01*
X179609Y-198564D01*
X172841D01*
G01X208496Y-190397D02*
Y-207897D01*
X217230D01*
G01X230363D02*
X229053Y-207605D01*
X227743Y-206439D01*
X226869Y-204397D01*
X226433Y-202064D01*
X226869Y-199730D01*
X227743Y-197689D01*
X229053Y-196522D01*
X230363Y-196231D01*
X231673Y-196522D01*
X232983Y-197689D01*
X233856Y-199730D01*
X234075Y-202064D01*
X233856Y-204397D01*
X232983Y-206439D01*
X231673Y-207605D01*
X230363Y-207897D01*
G01X242404Y-196231D02*
X245025Y-207897D01*
X247863Y-196231D01*
X250701Y-207897D01*
X253322Y-196231D01*
G01X278496Y-190397D02*
Y-207897D01*
X287230D01*
G01X300363D02*
X299053Y-207605D01*
X297743Y-206439D01*
X296869Y-204397D01*
X296433Y-202064D01*
X296869Y-199730D01*
X297743Y-197689D01*
X299053Y-196522D01*
X300363Y-196231D01*
X301673Y-196522D01*
X302983Y-197689D01*
X303856Y-199730D01*
X304075Y-202064D01*
X303856Y-204397D01*
X302983Y-206439D01*
X301673Y-207605D01*
X300363Y-207897D01*
G01X314588Y-205856D02*
X315680Y-207022D01*
X317208Y-207897D01*
X318518D01*
X319828Y-207314D01*
X320701Y-206439D01*
X321138Y-205273D01*
X320920Y-203522D01*
X320046Y-202647D01*
X316116Y-200897D01*
X315243Y-198855D01*
X315680Y-197397D01*
X316553Y-196522D01*
X317863Y-196231D01*
X319173Y-196522D01*
X320483Y-197397D01*
G01X332088Y-205856D02*
X333180Y-207022D01*
X334708Y-207897D01*
X336018D01*
X337328Y-207314D01*
X338201Y-206439D01*
X338638Y-205273D01*
X338420Y-203522D01*
X337546Y-202647D01*
X333616Y-200897D01*
X332743Y-198855D01*
X333180Y-197397D01*
X334053Y-196522D01*
X335363Y-196231D01*
X336673Y-196522D01*
X337983Y-197397D01*
G01X94686Y-164897D02*
Y-147397D01*
X100363Y-161980D01*
X106040Y-147397D01*
Y-164897D01*
G01X117863D02*
X116553Y-164605D01*
X115243Y-163439D01*
X114369Y-161397D01*
X113933Y-159064D01*
X114369Y-156730D01*
X115243Y-154689D01*
X116553Y-153522D01*
X117863Y-153231D01*
X119173Y-153522D01*
X120483Y-154689D01*
X121356Y-156730D01*
X121575Y-159064D01*
X121356Y-161397D01*
X120483Y-163439D01*
X119173Y-164605D01*
X117863Y-164897D01*
G01X139293Y-147397D02*
Y-164897D01*
G01Y-162273D02*
X138420Y-163731D01*
X137109Y-164605D01*
X135581Y-164897D01*
X133835Y-164314D01*
X132525Y-162856D01*
X131651Y-161106D01*
X131433Y-159064D01*
X131651Y-157022D01*
X132525Y-155272D01*
X133835Y-153814D01*
X135581Y-153231D01*
X137109Y-153522D01*
X138201Y-154106D01*
X139293Y-155272D01*
G01X149588Y-157022D02*
X156575D01*
X155920Y-154980D01*
X154828Y-153814D01*
X153300Y-153231D01*
X151771Y-153522D01*
X150461Y-154397D01*
X149588Y-156439D01*
X149151Y-158189D01*
Y-159939D01*
X149588Y-161689D01*
X150680Y-163439D01*
X151990Y-164605D01*
X153518Y-164897D01*
X155046Y-164314D01*
X156575Y-162564D01*
G01X170363Y-164897D02*
Y-147397D01*
G01X376163Y-209897D02*
Y-192397D01*
X373543Y-195897D01*
G01Y-209897D02*
X378783D01*
G01X396283D02*
Y-192397D01*
X388204Y-204939D01*
X399122D01*
G01X406360Y-207273D02*
X407669Y-208731D01*
X409198Y-209605D01*
X411163Y-209897D01*
X413128Y-209314D01*
X414656Y-208147D01*
X415748Y-206106D01*
X415966Y-203772D01*
X415530Y-201439D01*
X414438Y-199980D01*
X412909Y-198814D01*
X411381Y-198522D01*
X409853Y-198814D01*
X407888Y-199980D01*
X408543Y-192397D01*
X414438D01*
G01X431283Y-209897D02*
Y-192397D01*
X423204Y-204939D01*
X434122D01*
G01X441360Y-207273D02*
X442669Y-208731D01*
X444198Y-209605D01*
X446163Y-209897D01*
X448128Y-209314D01*
X449656Y-208147D01*
X450748Y-206106D01*
X450966Y-203772D01*
X450530Y-201439D01*
X449438Y-199980D01*
X447909Y-198814D01*
X446381Y-198522D01*
X444853Y-198814D01*
X442888Y-199980D01*
X443543Y-192397D01*
X449438D01*
G01X363046Y-164897D02*
Y-147397D01*
X368286D01*
X370033Y-148272D01*
X371343Y-150314D01*
X371780Y-152647D01*
X371343Y-154980D01*
X370251Y-156730D01*
X368286Y-157606D01*
X363046D01*
G01X389716Y-148856D02*
X388406Y-147980D01*
X386878Y-147397D01*
X385131D01*
X383166Y-148272D01*
X381638Y-149730D01*
X380546Y-151481D01*
X379673Y-154397D01*
X379454Y-157022D01*
X379891Y-159647D01*
X380546Y-161397D01*
X381856Y-163147D01*
X383385Y-164314D01*
X384913Y-164897D01*
X386441D01*
X387970Y-164314D01*
X389280Y-163439D01*
X390372Y-162273D01*
G01X404159Y-155564D02*
X405033Y-154689D01*
X405688Y-153231D01*
X406125Y-151188D01*
X405688Y-149439D01*
X404815Y-148272D01*
X403286Y-147397D01*
X397391D01*
Y-164897D01*
X404596D01*
X406125Y-163731D01*
X406998Y-161980D01*
X407435Y-159939D01*
X406998Y-157897D01*
X405688Y-156147D01*
X404159Y-155564D01*
X397391D01*
G01X413363Y-170730D02*
X426463D01*
G01X432391Y-164897D02*
Y-147397D01*
X442435Y-164897D01*
Y-147397D01*
G01X454913Y-164897D02*
X453166Y-164605D01*
X451638Y-163439D01*
X450328Y-161689D01*
X449454Y-159647D01*
X449018Y-157314D01*
Y-154980D01*
X449454Y-152647D01*
X450328Y-150605D01*
X451638Y-148856D01*
X453166Y-147689D01*
X454913Y-147397D01*
X456659Y-147689D01*
X458188Y-148856D01*
X459498Y-150605D01*
X460372Y-152647D01*
X460808Y-154980D01*
Y-157314D01*
X460372Y-159647D01*
X459498Y-161689D01*
X458188Y-163439D01*
X456659Y-164605D01*
X454913Y-164897D01*
G01X505754Y-147397D02*
X511213Y-164897D01*
X516672Y-147397D01*
G01X533080Y-164897D02*
X524346D01*
Y-147397D01*
X533080D01*
G01X529586Y-155855D02*
X524346D01*
G01X541846Y-164897D02*
Y-147397D01*
X547305D01*
X549051Y-148272D01*
X550143Y-149439D01*
X550580Y-151772D01*
X550143Y-154106D01*
X548833Y-155564D01*
X547305Y-156439D01*
X541846D01*
G01X547305D02*
X550580Y-164897D01*
G01X563713Y-165480D02*
X563276Y-165189D01*
Y-164605D01*
X563713Y-164314D01*
X564150Y-164605D01*
Y-165189D01*
X563713Y-165480D01*
G01X524128Y-207564D02*
X525875Y-209022D01*
X527840Y-209897D01*
X529586D01*
X531333Y-209022D01*
X532643Y-207564D01*
X533298Y-205522D01*
X532861Y-203481D01*
X531770Y-201730D01*
X529805Y-200564D01*
X527185Y-199980D01*
X525656Y-198814D01*
X525001Y-196772D01*
X525438Y-194730D01*
X526530Y-193272D01*
X528058Y-192397D01*
X529586D01*
X531115Y-192980D01*
X532425Y-194439D01*
G01X540754Y-209897D02*
X546213Y-192397D01*
X551672Y-209897D01*
G01X549706Y-203772D02*
X542719D01*
G01X665546Y-192397D02*
Y-209897D01*
X674280D01*
G01X682610Y-206397D02*
X683919Y-208439D01*
X685666Y-209605D01*
X687631Y-209897D01*
X689378Y-209605D01*
X691125Y-208147D01*
X692216Y-206397D01*
X692435Y-204647D01*
X691998Y-202606D01*
X690470Y-201147D01*
X688941Y-200564D01*
X686976D01*
G01X688941D02*
X690251Y-199689D01*
X691343Y-198231D01*
X691780Y-196481D01*
X691343Y-194730D01*
X690251Y-193272D01*
X688286Y-192397D01*
X686321Y-192689D01*
X684356Y-193856D01*
G01X630546Y-147397D02*
Y-164897D01*
X639280D01*
G01X656343D02*
Y-153231D01*
G01Y-155272D02*
X655470Y-154106D01*
X654159Y-153522D01*
X652631Y-153231D01*
X651103Y-153814D01*
X649793Y-154980D01*
X648919Y-156730D01*
X648483Y-159064D01*
X648919Y-161397D01*
X649793Y-163147D01*
X651103Y-164314D01*
X652631Y-164897D01*
X654159Y-164605D01*
X655470Y-163731D01*
X656343Y-162564D01*
G01X665328Y-170147D02*
X666638Y-170730D01*
X668385Y-170147D01*
X669476Y-168981D01*
X670350Y-167522D01*
X671659Y-162856D01*
X674498Y-153231D01*
G01X667511D02*
X671659Y-162856D01*
G01X684138Y-157022D02*
X691125D01*
X690470Y-154980D01*
X689378Y-153814D01*
X687850Y-153231D01*
X686321Y-153522D01*
X685011Y-154397D01*
X684138Y-156439D01*
X683701Y-158189D01*
Y-159939D01*
X684138Y-161689D01*
X685230Y-163439D01*
X686540Y-164605D01*
X688068Y-164897D01*
X689596Y-164314D01*
X691125Y-162564D01*
G01X701856Y-164897D02*
Y-153231D01*
G01Y-155564D02*
X702948Y-154397D01*
X704040Y-153522D01*
X705568Y-153231D01*
X706659Y-153522D01*
X707970Y-154397D01*
G01X719138Y-162856D02*
X720230Y-164022D01*
X721758Y-164897D01*
X723068D01*
X724378Y-164314D01*
X725251Y-163439D01*
X725688Y-162273D01*
X725470Y-160522D01*
X724596Y-159647D01*
X720666Y-157897D01*
X719793Y-155855D01*
X720230Y-154397D01*
X721103Y-153522D01*
X722413Y-153231D01*
X723723Y-153522D01*
X725033Y-154397D01*
G01X790596Y-209897D02*
Y-192397D01*
X796055D01*
X797801Y-193272D01*
X798893Y-194439D01*
X799330Y-196772D01*
X798893Y-199106D01*
X797583Y-200564D01*
X796055Y-201439D01*
X790596D01*
G01X796055D02*
X799330Y-209897D01*
G01X809188Y-202022D02*
X816175D01*
X815520Y-199980D01*
X814428Y-198814D01*
X812900Y-198231D01*
X811371Y-198522D01*
X810061Y-199397D01*
X809188Y-201439D01*
X808751Y-203189D01*
Y-204939D01*
X809188Y-206689D01*
X810280Y-208439D01*
X811590Y-209605D01*
X813118Y-209897D01*
X814646Y-209314D01*
X816175Y-207564D01*
G01X826033Y-209897D02*
Y-192397D01*
G01Y-201147D02*
X827125Y-199397D01*
X828435Y-198522D01*
X829745Y-198231D01*
X831709Y-198814D01*
X833020Y-199980D01*
X833893Y-202022D01*
Y-204355D01*
X833456Y-206689D01*
X832583Y-208439D01*
X831055Y-209605D01*
X829745Y-209897D01*
X828435Y-209605D01*
X827125Y-208731D01*
X826033Y-207273D01*
G01X844188Y-202022D02*
X851175D01*
X850520Y-199980D01*
X849428Y-198814D01*
X847900Y-198231D01*
X846371Y-198522D01*
X845061Y-199397D01*
X844188Y-201439D01*
X843751Y-203189D01*
Y-204939D01*
X844188Y-206689D01*
X845280Y-208439D01*
X846590Y-209605D01*
X848118Y-209897D01*
X849646Y-209314D01*
X851175Y-207564D01*
G01X868456Y-199689D02*
X866928Y-198522D01*
X865618Y-198231D01*
X863871Y-198814D01*
X862561Y-199980D01*
X861688Y-202022D01*
X861469Y-204064D01*
X861688Y-206106D01*
X862561Y-207856D01*
X863871Y-209314D01*
X865618Y-209897D01*
X867146Y-209314D01*
X868456Y-208147D01*
G01X885956Y-199689D02*
X884428Y-198522D01*
X883118Y-198231D01*
X881371Y-198814D01*
X880061Y-199980D01*
X879188Y-202022D01*
X878969Y-204064D01*
X879188Y-206106D01*
X880061Y-207856D01*
X881371Y-209314D01*
X883118Y-209897D01*
X884646Y-209314D01*
X885956Y-208147D01*
G01X903893Y-209897D02*
Y-198231D01*
G01Y-200272D02*
X903020Y-199106D01*
X901709Y-198522D01*
X900181Y-198231D01*
X898653Y-198814D01*
X897343Y-199980D01*
X896469Y-201730D01*
X896033Y-204064D01*
X896469Y-206397D01*
X897343Y-208147D01*
X898653Y-209314D01*
X900181Y-209897D01*
X901709Y-209605D01*
X903020Y-208731D01*
X903893Y-207564D01*
G01X781410Y-164897D02*
Y-147397D01*
X785776D01*
X787523Y-148272D01*
X788833Y-149439D01*
X789925Y-151188D01*
X790798Y-153231D01*
X791016Y-156147D01*
X790798Y-159064D01*
X789925Y-161106D01*
X788833Y-162856D01*
X787523Y-164022D01*
X785776Y-164897D01*
X781410D01*
G01X800438Y-157022D02*
X807425D01*
X806770Y-154980D01*
X805678Y-153814D01*
X804150Y-153231D01*
X802621Y-153522D01*
X801311Y-154397D01*
X800438Y-156439D01*
X800001Y-158189D01*
Y-159939D01*
X800438Y-161689D01*
X801530Y-163439D01*
X802840Y-164605D01*
X804368Y-164897D01*
X805896Y-164314D01*
X807425Y-162564D01*
G01X817938Y-162856D02*
X819030Y-164022D01*
X820558Y-164897D01*
X821868D01*
X823178Y-164314D01*
X824051Y-163439D01*
X824488Y-162273D01*
X824270Y-160522D01*
X823396Y-159647D01*
X819466Y-157897D01*
X818593Y-155855D01*
X819030Y-154397D01*
X819903Y-153522D01*
X821213Y-153231D01*
X822523Y-153522D01*
X823833Y-154397D01*
G01X838713Y-153231D02*
Y-164897D01*
G01Y-148564D02*
X838276Y-148272D01*
Y-147689D01*
X838713Y-147397D01*
X839150Y-147689D01*
Y-148272D01*
X838713Y-148564D01*
G01X853156Y-169272D02*
X854685Y-170439D01*
X856431Y-170730D01*
X857959Y-170439D01*
X859270Y-168981D01*
X860143Y-166939D01*
Y-153231D01*
G01Y-155564D02*
X859270Y-154397D01*
X857959Y-153522D01*
X856431Y-153231D01*
X854685Y-153814D01*
X853593Y-154980D01*
X852719Y-157022D01*
X852283Y-159064D01*
X852501Y-160814D01*
X853375Y-162856D01*
X854685Y-164314D01*
X856431Y-164897D01*
X857741Y-164605D01*
X859270Y-163439D01*
X860143Y-162273D01*
G01X870001Y-164897D02*
Y-153231D01*
G01Y-156147D02*
X870875Y-154689D01*
X872185Y-153522D01*
X873931Y-153231D01*
X875459Y-153522D01*
X876770Y-154689D01*
X877425Y-156730D01*
Y-164897D01*
G01X887938Y-157022D02*
X894925D01*
X894270Y-154980D01*
X893178Y-153814D01*
X891650Y-153231D01*
X890121Y-153522D01*
X888811Y-154397D01*
X887938Y-156439D01*
X887501Y-158189D01*
Y-159939D01*
X887938Y-161689D01*
X889030Y-163439D01*
X890340Y-164605D01*
X891868Y-164897D01*
X893396Y-164314D01*
X894925Y-162564D01*
G01X905656Y-164897D02*
Y-153231D01*
G01Y-155564D02*
X906748Y-154397D01*
X907840Y-153522D01*
X909368Y-153231D01*
X910459Y-153522D01*
X911770Y-154397D01*
G01X952413Y-192397D02*
X950666Y-192980D01*
X949356Y-194439D01*
X948483Y-196188D01*
X947828Y-198522D01*
X947610Y-201147D01*
X947828Y-203772D01*
X948483Y-206106D01*
X949356Y-207856D01*
X950666Y-209314D01*
X952413Y-209897D01*
X954159Y-209314D01*
X955470Y-207856D01*
X956343Y-206106D01*
X956998Y-203772D01*
X957216Y-201147D01*
X956998Y-198522D01*
X956343Y-196188D01*
X955470Y-194439D01*
X954159Y-192980D01*
X952413Y-192397D01*
G01X969913Y-209897D02*
X971441Y-209605D01*
X973188Y-208731D01*
X974280Y-207273D01*
X974716Y-205230D01*
X974280Y-203189D01*
X972970Y-201439D01*
X971005Y-200564D01*
X968821D01*
X967511Y-199980D01*
X966419Y-198522D01*
X965983Y-196481D01*
X966638Y-194439D01*
X968166Y-192980D01*
X969913Y-192397D01*
X971659Y-192980D01*
X973188Y-194439D01*
X973843Y-196481D01*
X973406Y-198522D01*
X972315Y-199980D01*
X971005Y-200564D01*
X968821D01*
X966856Y-201439D01*
X965546Y-203189D01*
X965110Y-205230D01*
X965546Y-207273D01*
X966638Y-208731D01*
X968385Y-209605D01*
X969913Y-209897D01*
G01X983483Y-210480D02*
X991343Y-192397D01*
G01X1004913D02*
X1003166Y-192980D01*
X1001856Y-194439D01*
X1000983Y-196188D01*
X1000328Y-198522D01*
X1000110Y-201147D01*
X1000328Y-203772D01*
X1000983Y-206106D01*
X1001856Y-207856D01*
X1003166Y-209314D01*
X1004913Y-209897D01*
X1006659Y-209314D01*
X1007970Y-207856D01*
X1008843Y-206106D01*
X1009498Y-203772D01*
X1009716Y-201147D01*
X1009498Y-198522D01*
X1008843Y-196188D01*
X1007970Y-194439D01*
X1006659Y-192980D01*
X1004913Y-192397D01*
G01X1022413Y-209897D02*
Y-192397D01*
X1019793Y-195897D01*
G01Y-209897D02*
X1025033D01*
G01X1035983Y-210480D02*
X1043843Y-192397D01*
G01X1053265Y-195314D02*
X1054575Y-193564D01*
X1056103Y-192689D01*
X1057850Y-192397D01*
X1060033Y-192980D01*
X1061561Y-194439D01*
X1061998Y-196188D01*
X1061780Y-197939D01*
X1060906Y-199397D01*
X1056540Y-202314D01*
X1054575Y-204355D01*
X1053265Y-207273D01*
X1052828Y-209897D01*
X1061998D01*
G01X1074913Y-192397D02*
X1073166Y-192980D01*
X1071856Y-194439D01*
X1070983Y-196188D01*
X1070328Y-198522D01*
X1070110Y-201147D01*
X1070328Y-203772D01*
X1070983Y-206106D01*
X1071856Y-207856D01*
X1073166Y-209314D01*
X1074913Y-209897D01*
X1076659Y-209314D01*
X1077970Y-207856D01*
X1078843Y-206106D01*
X1079498Y-203772D01*
X1079716Y-201147D01*
X1079498Y-198522D01*
X1078843Y-196188D01*
X1077970Y-194439D01*
X1076659Y-192980D01*
X1074913Y-192397D01*
G01X1092413Y-209897D02*
Y-192397D01*
X1089793Y-195897D01*
G01Y-209897D02*
X1095033D01*
G01X1112533D02*
Y-192397D01*
X1104454Y-204939D01*
X1115372D01*
G01X1000110Y-164897D02*
Y-147397D01*
X1004476D01*
X1006223Y-148272D01*
X1007533Y-149439D01*
X1008625Y-151188D01*
X1009498Y-153231D01*
X1009716Y-156147D01*
X1009498Y-159064D01*
X1008625Y-161106D01*
X1007533Y-162856D01*
X1006223Y-164022D01*
X1004476Y-164897D01*
X1000110D01*
G01X1026343D02*
Y-153231D01*
G01Y-155272D02*
X1025470Y-154106D01*
X1024159Y-153522D01*
X1022631Y-153231D01*
X1021103Y-153814D01*
X1019793Y-154980D01*
X1018919Y-156730D01*
X1018483Y-159064D01*
X1018919Y-161397D01*
X1019793Y-163147D01*
X1021103Y-164314D01*
X1022631Y-164897D01*
X1024159Y-164605D01*
X1025470Y-163731D01*
X1026343Y-162564D01*
G01X1039913Y-147397D02*
Y-164897D01*
G01X1036856Y-153231D02*
X1042970D01*
G01X1054138Y-157022D02*
X1061125D01*
X1060470Y-154980D01*
X1059378Y-153814D01*
X1057850Y-153231D01*
X1056321Y-153522D01*
X1055011Y-154397D01*
X1054138Y-156439D01*
X1053701Y-158189D01*
Y-159939D01*
X1054138Y-161689D01*
X1055230Y-163439D01*
X1056540Y-164605D01*
X1058068Y-164897D01*
X1059596Y-164314D01*
X1061125Y-162564D01*
G54D19*
G01X123999Y1054050D02*
G03X126001Y1053075I2414J2414D01*
G01X126002D01*
G03X126413Y1053050I412J3389D01*
G01X127000D01*
G02X129042Y1052204I-1J-2890D01*
G01Y1052203D01*
G02X129999Y1049893I-2309J-2310D01*
G01Y1047141D01*
G02X128947Y1044602I-3590J0D01*
G01X128948Y1044601D01*
X125273Y1040926D01*
G03X123300Y1036163I4763J-4763D01*
G01Y819233D01*
G02X119600Y810300I-12633J0D01*
G01X117582Y808282D01*
G03X117051Y807000I1282J-1282D01*
G01Y520376D01*
G02X115769Y517279I-4379J-1D01*
G01X113708Y515218D01*
X79369Y480880D01*
G02X76352Y479631I-3016J3017D01*
G01X31040D01*
G03X29777Y479107I1J-1786D01*
G02X29561Y478924I-1203J1201D01*
G02X27936Y478404I-1625J2278D01*
G01X26299D01*
G01X123999Y1050650D02*
X124811Y1051463D01*
G02X125745Y1051850I934J-934D01*
G01X126999D01*
Y1051849D01*
G02X128194Y1051355I1J-1690D01*
G02X128799Y1049894I-1461J-1461D01*
G01Y1047140D01*
G02X128099Y1045450I-2390J0D01*
G01X124424Y1041775D01*
G03X122100Y1036164I5612J-5611D01*
G01Y819232D01*
X122099Y819233D01*
G02X118752Y811148I-11433J-2D01*
G01X118751Y811149D01*
X116733Y809131D01*
G03X115851Y807000I2131J-2130D01*
G01Y520376D01*
G02X114920Y518128I-3179J0D01*
G01X114270Y517478D01*
X114269D01*
X78520Y481729D01*
G02X76352Y480831I-2168J2168D01*
G01X31039D01*
G03X28927Y479956I0J-2987D01*
G02X28573Y479809I-354J353D01*
G01X27807D01*
G02X27181Y480068I0J886D01*
G01X27062Y480187D01*
G02X26921Y480528I342J341D01*
G01Y480632D01*
G03X26884Y480817I-483J0D01*
G01X26720Y481213D01*
G03X26686Y481386I-452J1D01*
G01X26515Y481798D01*
G01X127999Y645550D02*
G03X129000Y647967I-2417J2417D01*
G01Y648799D01*
G03X128361Y650341I-2180J0D01*
G01X126951Y651751D01*
G02X125900Y654290I2539J2538D01*
G01Y657699D01*
G02X127099Y660597I4097J2D01*
G01X127551Y661049D01*
X127552Y661048D01*
G02X129850Y662000I2298J-2297D01*
G01X136626D01*
G02X139648Y660748I0J-4273D01*
G01X139649Y660749D01*
X147799Y652599D01*
X147798Y652598D01*
G02X149471Y648562I-4037J-4038D01*
G01Y642378D01*
G03X151199Y640650I1728J0D01*
G01X154386D01*
G02X157648Y639299I0J-4614D01*
G02X158999Y636037I-3263J-3262D01*
G01Y612171D01*
G02X157499Y608550I-5121J0D01*
G01X148787Y599837D01*
G03X147839Y597550I2287J-2288D01*
G01Y546149D01*
G02X146318Y542478I-5193J1D01*
G01X69944Y466104D01*
G02X64582Y463883I-5362J5362D01*
G01X30153D01*
G03X29733Y463708I2J-596D01*
G02X27841Y462948I-1835J1833D01*
G01X27265Y462961D01*
G03X26486Y462648I-23J-1068D01*
G01X131400Y644600D02*
G02X130200Y647497I2897J2897D01*
G01Y648800D01*
G03X129210Y651190I-3380J0D01*
G01X127800Y652600D01*
G02X127100Y654290I1690J1690D01*
G01Y657700D01*
G02X127948Y659748I2897J0D01*
G01X128400Y660200D01*
G02X129849Y660800I1449J-1449D01*
G01X136627D01*
G02X138800Y659900I0J-3073D01*
G01X146950Y651750D01*
G02X148271Y648561I-3189J-3189D01*
G01Y642378D01*
G03X151199Y639450I2928J0D01*
G01X154385D01*
G02X156799Y638450I0J-3414D01*
G02X157799Y636036I-2414J-2414D01*
G01Y612172D01*
G02X156651Y609398I-3921J-2D01*
G01X156650Y609399D01*
X147938Y600686D01*
G03X146640Y597550I3136J-3135D01*
G01X146639D01*
Y589784D01*
G02X146269Y589044I-940J7D01*
G03X145899Y588304I570J-748D01*
G01Y586954D01*
G03X146269Y586214I940J7D01*
G02X146639Y585474I-570J-748D01*
G01Y584124D01*
G02X146269Y583384I-940J7D01*
G03X145899Y582644I570J-748D01*
G01Y581294D01*
G03X146269Y580554I940J7D01*
G02X146639Y579814I-570J-748D01*
G01Y573937D01*
G02X146269Y573197I-940J7D01*
G03X145899Y572457I570J-747D01*
G01Y571107D01*
G03X146269Y570367I940J7D01*
G02X146639Y569627I-570J-747D01*
G01Y568277D01*
G02X146269Y567537I-940J7D01*
G03X145899Y566797I570J-748D01*
G01Y565447D01*
G03X146269Y564707I940J7D01*
G02X146639Y563967I-570J-748D01*
G01Y562617D01*
G02X146269Y561877I-940J7D01*
G03X145899Y561137I570J-748D01*
G01Y559787D01*
G03X146269Y559047I940J7D01*
G02X146639Y558307I-570J-748D01*
G01Y556957D01*
G02X146269Y556217I-940J7D01*
G03X145899Y555477I570J-747D01*
G01Y554127D01*
G03X146269Y553387I940J7D01*
G02X146639Y552647I-570J-747D01*
G01Y546150D01*
G02X145469Y543327I-3993J1D01*
G01X69095Y466953D01*
G02X64580Y465083I-4515J4515D01*
G01X30154D01*
G03X28884Y464557I0J-1796D01*
G02X26914I-985J985D01*
G02X26499Y465559I1002J1002D01*
G01Y466250D01*
G01X26599Y525648D02*
Y525867D01*
G02X28158Y527061I1237J0D01*
G03X29562Y526875I1404J5202D01*
G01X37519D01*
G02X38259Y526505I-7J-940D01*
G03X38999Y526135I747J570D01*
G01X40349D01*
G03X41089Y526505I-7J940D01*
G02X41829Y526875I747J-570D01*
G01X43179D01*
G02X43919Y526505I-7J-940D01*
G03X44659Y526135I747J570D01*
G01X46009D01*
G03X46749Y526505I-7J940D01*
G02X47489Y526875I747J-570D01*
G01X48839D01*
G02X49579Y526505I-7J-940D01*
G03X50319Y526135I747J570D01*
G01X51669D01*
G03X52409Y526505I-7J940D01*
G02X53149Y526875I747J-570D01*
G01X54499D01*
G02X57359Y525691I1J-4044D01*
G01X58499Y524550D01*
G03X73470Y518350I14969J14970D01*
G01X76557D01*
G02X77297Y517980I-8J-940D01*
G03X78037Y517610I747J570D01*
G01X79387D01*
G03X80127Y517980I-8J940D01*
G02X80867Y518350I747J-570D01*
G01X82217D01*
G02X82957Y517980I-8J-940D01*
G03X83697Y517610I747J570D01*
G01X85047D01*
G03X85787Y517980I-8J940D01*
G02X86527Y518350I747J-570D01*
G01X87877D01*
G02X88617Y517980I-7J-940D01*
G03X89357Y517610I747J570D01*
G01X90707D01*
G03X91447Y517980I-7J940D01*
G02X92187Y518350I747J-570D01*
G01X95117D01*
G02X96201Y517901I0J-1533D01*
G02X96800Y516455I-1446J-1446D01*
G01Y515900D01*
G02X95951Y513852I-2897J1D01*
G01X95500Y513400D01*
G01X98900D02*
G02X98000Y515573I2173J2173D01*
G01Y516456D01*
G03X97049Y518749I-3245J-2D01*
G01Y518750D01*
G03X95117Y519550I-1932J-1933D01*
G01X73469D01*
G02X59348Y525399I0J19970D01*
G01X58208Y526540D01*
G03X54499Y528074I-3706J-3710D01*
G01Y528075D01*
X29561D01*
G02X26599Y529302I0J4189D01*
M02*
